FILE_TYPE = MULTI_PHYS_TABLE;
PART 'RES'
{========================================================================================}
:VALUE     | TOLERANCE | WATTAGE | PACK_TYPE | MATERIAL | PART_NUMBER    = ENVCOMP                            | PART_NUMBER  | JEDEC_TYPE | ALT_SYMBOLS                   | VALUE    | TOL     | WATTAGE | CLASS      | DESCRIPTION                                             | HEIGHT     | COMPONENT_TYPE | LEAD_LENGTH | LPID   | SPEED_URL                                                                                                                       | STATUS        | RPL   | AML   | BUS_UNIT           | DAYS  ;
{========================================================================================}
'0.0'     | '5%'      | '1/16W' | '0402'    | 'CHIP'   | 'G21497-005'(!) = 'YES;YES;YES;UNK;OK;VLD'           | 'G21497-005' | 'SMR0402A' | '(SMX0402,SMX0402A,SMX0402B)' | '0.0'    | '5%'    | '1/16W' | 'DISCRETE' | 'RES_D,0402,0.0OHM,5.00%,1/16W'                         | '0.017 IN' | 'CHIP0402'     | ''          | '1141' | 'http://speed.intel.com:8081/speed/module/pdm/item/pdm_item_detail_direct.asp?item_cde=G21497-005&item_rev=01&url_param=unused' | 'UNQUAL'      | 'NO'  | '3'   | 'GMPO_BD_EXMPFREE' | '???'
'0.0'     | '5%'      | '1/16W' | '0402'    | 'EMPTY'  | 'G21497-005'(!) = 'YES;YES;YES;UNK;OK;VLD'           | 'G21497-005' | 'SMR0402A' | '(SMX0402,SMX0402A,SMX0402B)' | 'NA'     | '5%'    | '1/16W' | 'DISCRETE' | 'RES_D,0402,0.0OHM,5.00%,1/16W'                         | '0.017 IN' | 'CHIP0402'     | ''          | '1141' | 'http://speed.intel.com:8081/speed/module/pdm/item/pdm_item_detail_direct.asp?item_cde=G21497-005&item_rev=01&url_param=unused' | 'UNQUAL'      | 'NO'  | '3'   | 'GMPO_BD_EXMPFREE' | '???'
'3.3K'    | '5%'      | '1/16W' | '0402'    | 'EMPTY'  | 'G21497-013'(!) = 'YES;YES;YES;UNK;OK;VLD'           | 'G21497-013' | 'SMR0402A' | '(SMX0402,SMX0402A,SMX0402B)' | 'NA'     | '5%'    | '1/16W' | 'DISCRETE' | 'RES_D,0402,3.3KOHM,5.00%,1/16W'                        | '0.017 IN' | 'CHIP0402'     | ''          | '1141' | 'http://speed.intel.com:8081/speed/module/pdm/item/pdm_item_detail_direct.asp?item_cde=G21497-013&item_rev=01&url_param=unused' | 'UNQUAL'      | 'NO'  | '3'   | 'GMPO_BD_EXMPFREE' | '???'
'3.3K'    | '5%'      | '1/16W' | '0402'    | 'CHIP'   | 'G21497-013'(!) = 'YES;YES;YES;UNK;OK;VLD'           | 'G21497-013' | 'SMR0402A' | '(SMX0402,SMX0402A,SMX0402B)' | '3.3K'   | '5%'    | '1/16W' | 'DISCRETE' | 'RES_D,0402,3.3KOHM,5.00%,1/16W'                        | '0.017 IN' | 'CHIP0402'     | ''          | '1141' | 'http://speed.intel.com:8081/speed/module/pdm/item/pdm_item_detail_direct.asp?item_cde=G21497-013&item_rev=01&url_param=unused' | 'UNQUAL'      | 'NO'  | '3'   | 'GMPO_BD_EXMPFREE' | '???'
'2.2'     | '5%'      | '1/16W' | '0402'    | 'CHIP'   | 'G21497-016'(!) = 'YES;YES;YES;UNK;OK;VLD'           | 'G21497-016' | 'SMR0402A' | '(SMX0402,SMX0402A,SMX0402B)' | '2.2'    | '5%'    | '1/16W' | 'DISCRETE' | 'RES_D,0402,2.2OHM,5.00%,1/16W'                         | '0.017 IN' | 'CHIP0402'     | ''          | '1141' | 'http://speed.intel.com:8081/speed/module/pdm/item/pdm_item_detail_direct.asp?item_cde=G21497-016&item_rev=01&url_param=unused' | 'DESIGN'      | 'NO'  | '3'   | 'GMPO_BD_EXMPFREE' | '???'
'2.2'     | '5%'      | '1/16W' | '0402'    | 'EMPTY'  | 'G21497-016'(!) = 'YES;YES;YES;UNK;OK;VLD'           | 'G21497-016' | 'SMR0402A' | '(SMX0402,SMX0402A,SMX0402B)' | 'NA'     | '5%'    | '1/16W' | 'DISCRETE' | 'RES_D,0402,2.2OHM,5.00%,1/16W'                         | '0.017 IN' | 'CHIP0402'     | ''          | '1141' | 'http://speed.intel.com:8081/speed/module/pdm/item/pdm_item_detail_direct.asp?item_cde=G21497-016&item_rev=01&url_param=unused' | 'DESIGN'      | 'NO'  | '3'   | 'GMPO_BD_EXMPFREE' | '???'
'33.0K'   | '5%'      | '1/16W' | '0402'    | 'CHIP'   | 'G21497-023'(!) = 'YES;YES;YES;UNK;OK;VLD'           | 'G21497-023' | 'SMR0402A' | '(SMX0402,SMX0402A,SMX0402B)' | '33.0K'  | '5%'    | '1/16W' | 'DISCRETE' | 'RES_D,0402,33.0KOHM,5.00%,1/16W'                       | '0.017 IN' | 'CHIP0402'     | ''          | '1141' | 'http://speed.intel.com:8081/speed/module/pdm/item/pdm_item_detail_direct.asp?item_cde=G21497-023&item_rev=01&url_param=unused' | 'DESIGN'      | 'NO'  | '3'   | 'GMPO_BD_EXMPFREE' | '???'
'33.0K'   | '5%'      | '1/16W' | '0402'    | 'EMPTY'  | 'G21497-023'(!) = 'YES;YES;YES;UNK;OK;VLD'           | 'G21497-023' | 'SMR0402A' | '(SMX0402,SMX0402A,SMX0402B)' | 'NA'     | '5%'    | '1/16W' | 'DISCRETE' | 'RES_D,0402,33.0KOHM,5.00%,1/16W'                       | '0.017 IN' | 'CHIP0402'     | ''          | '1141' | 'http://speed.intel.com:8081/speed/module/pdm/item/pdm_item_detail_direct.asp?item_cde=G21497-023&item_rev=01&url_param=unused' | 'DESIGN'      | 'NO'  | '3'   | 'GMPO_BD_EXMPFREE' | '???'
'470.0'   | '5%'      | '1/16W' | '0402'    | 'CHIP'   | 'G21497-024'(!) = 'YES;YES;YES;UNK;OK;VLD'           | 'G21497-024' | 'SMR0402A' | '(SMX0402,SMX0402A,SMX0402B)' | '470.0'  | '5%'    | '1/16W' | 'DISCRETE' | 'RES_D,0402,470.0OHM,5.00%,1/16W'                       | '0.017 IN' | 'CHIP0402'     | ''          | '1141' | 'http://speed.intel.com:8081/speed/module/pdm/item/pdm_item_detail_direct.asp?item_cde=G21497-024&item_rev=01&url_param=unused' | 'UNQUAL'      | 'NO'  | '3'   | 'GMPO_BD_EXMPFREE' | '???'
'470.0'   | '5%'      | '1/16W' | '0402'    | 'EMPTY'  | 'G21497-024'(!) = 'YES;YES;YES;UNK;OK;VLD'           | 'G21497-024' | 'SMR0402A' | '(SMX0402,SMX0402A,SMX0402B)' | 'NA'     | '5%'    | '1/16W' | 'DISCRETE' | 'RES_D,0402,470.0OHM,5.00%,1/16W'                       | '0.017 IN' | 'CHIP0402'     | ''          | '1141' | 'http://speed.intel.com:8081/speed/module/pdm/item/pdm_item_detail_direct.asp?item_cde=G21497-024&item_rev=01&url_param=unused' | 'UNQUAL'      | 'NO'  | '3'   | 'GMPO_BD_EXMPFREE' | '???'
'330'     | '5%'      | '1/16W' | '0402'    | 'EMPTY'  | 'G21497-028'(!) = 'YES;YES;YES;UNK;OK;VLD'           | 'G21497-028' | 'SMR0402A' | '(SMX0402,SMX0402A,SMX0402B)' | 'NA'     | '5%'    | '1/16W' | 'DISCRETE' | 'RES_D,0402,330.00OHM,5.00%,1/16W'                      | '0.016 IN' | 'CHIP0402'     | ''          | '1141' | 'http://speed.intel.com:8081/speed/module/pdm/item/pdm_item_detail_direct.asp?item_cde=G21497-028&item_rev=01&url_param=unused' | 'UNQUAL'      | 'NO'  | '2'   | 'GMPO_BD_EXMPFREE' | '???'
'330.0'   | '5%'      | '1/16W' | '0402'    | 'CHIP'   | 'G21497-028'(!) = 'YES;YES;YES;UNK;OK;VLD'           | 'G21497-028' | 'SMR0402A' | '(SMX0402,SMX0402A,SMX0402B)' | '330.0'  | '5%'    | '1/16W' | 'DISCRETE' | 'RES_D,0402,330.0OHM,5.00%,1/16W'                       | '0.017 IN' | 'CHIP0402'     | ''          | '1141' | 'http://speed.intel.com:8081/speed/module/pdm/item/pdm_item_detail_direct.asp?item_cde=G21497-028&item_rev=01&url_param=unused' | 'UNQUAL'      | 'NO'  | '2'   | 'GMPO_BD_EXMPFREE' | '???'
'330'     | '5%'      | '1/16W' | '0402'    | 'CHIP'   | 'G21497-028'(!) = 'YES;YES;YES;UNK;OK;VLD'           | 'G21497-028' | 'SMR0402A' | '(SMX0402,SMX0402A,SMX0402B)' | '300'    | '5%'    | '1/16W' | 'DISCRETE' | 'RES_D,0402,330.00OHM,5.00%,1/16W'                      | '0.016 IN' | 'CHIP0402'     | ''          | '1141' | 'http://speed.intel.com:8081/speed/module/pdm/item/pdm_item_detail_direct.asp?item_cde=G21497-028&item_rev=01&url_param=unused' | 'UNQUAL'      | 'NO'  | '2'   | 'GMPO_BD_EXMPFREE' | '???'
'330.0'   | '5%'      | '1/16W' | '0402'    | 'EMPTY'  | 'G21497-028'(!) = 'YES;YES;YES;UNK;OK;VLD'           | 'G21497-028' | 'SMR0402A' | '(SMX0402,SMX0402A,SMX0402B)' | 'NA'     | '5%'    | '1/16W' | 'DISCRETE' | 'RES_D,0402,330.0OHM,5.00%,1/16W'                       | '0.017 IN' | 'CHIP0402'     | ''          | '1141' | 'http://speed.intel.com:8081/speed/module/pdm/item/pdm_item_detail_direct.asp?item_cde=G21497-028&item_rev=01&url_param=unused' | 'UNQUAL'      | 'NO'  | '2'   | 'GMPO_BD_EXMPFREE' | '???'
'51'      | '5.0%'    | '1/16W' | '0402'    | 'CHIP'   | 'G21497-048'(!) = 'YES;YES;YES;UNK;OK;VLD'           | 'G21497-048' | 'SMR0402A' | '(SMX0402,SMX0402A,SMX0402B)' | '51'     | '5.0%'  | '1/16W' | 'DISCRETE' | 'RES_D,0402,51.00OHM,5.00%,1/16W,'                      | '0.016 IN' | 'CHIP0402'     | ''          | '1141' | 'http://speed.intel.com:8081/speed/module/pdm/item/pdm_item_detail_direct.asp?item_cde=G21497-048&item_rev=01&url_param=unused' | 'DESIGN'      | 'NO'  | '2'   | 'GMPO_BD_EXMPFREE' | '???'
'51'      | '5.0%'    | '1/16W' | '0402'    | 'EMPTY'  | 'G21497-048'(!) = 'YES;YES;YES;UNK;OK;VLD'           | 'G21497-048' | 'SMR0402A' | '(SMX0402,SMX0402A,SMX0402B)' | 'NA'     | '5.0%'  | '1/16W' | 'DISCRETE' | 'RES_D,0402,51.00OHM,5.00%,1/16W,'                      | '0.016 IN' | 'CHIP0402'     | ''          | '1141' | 'http://speed.intel.com:8081/speed/module/pdm/item/pdm_item_detail_direct.asp?item_cde=G21497-048&item_rev=01&url_param=unused' | 'DESIGN'      | 'NO'  | '2'   | 'GMPO_BD_EXMPFREE' | '???'
'560'     | '5%'      | '1/16W' | '0402'    | 'CHIP'   | 'G21497-062'(!) = ''                                 | 'G21497-062' | 'SMR0402A' | '(SMX0402,SMX0402A)'          | '560'    | '5%'    | '1/16W' | 'DISCRETE' | 'RES_D,0402,560.00OHM,5.00%,1/16W,'                     | '0.016 IN' | 'CHIP0402'     | ''          | '1141' | 'http://speed.intel.com:8081/speed/module/pdm/item/pdm_item_detail_direct.asp?item_cde=G21497-062&item_rev=01&url_param=unused' | ''            | ''    | ''    | ''                 | ''   
'560'     | '5%'      | '1/16W' | '0402'    | 'EMPTY'  | 'G21497-062'(!) = ''                                 | 'G21497-062' | 'SMR0402A' | '(SMX0402,SMX0402A)'          | 'NA'     | '5%'    | '1/16W' | 'DISCRETE' | 'RES_D,0402,560.00OHM,5.00%,1/16W,'                     | '0.016 IN' | 'CHIP0402'     | ''          | '1141' | 'http://speed.intel.com:8081/speed/module/pdm/item/pdm_item_detail_direct.asp?item_cde=G21497-062&item_rev=01&url_param=unused' | ''            | ''    | ''    | ''                 | ''   
'2.0K'    | '1%'      | '1/16W' | '0402'    | 'CHIP'   | 'G21796-001'(!) = 'YES;YES;YES;UNK;OK;VLD'           | 'G21796-001' | 'SMR0402A' | '(SMX0402,SMX0402A,SMX0402B)' | '2.0K'   | '1%'    | '1/16W' | 'DISCRETE' | 'RES_D,0402,2.0KOHM,1.00%,1/16W'                        | '0.017 IN' | 'CHIP0402'     | ''          | '1141' | 'http://speed.intel.com:8081/speed/module/pdm/item/pdm_item_detail_direct.asp?item_cde=G21796-001&item_rev=01&url_param=unused' | 'CONDITIONAL' | 'NO'  | '3'   | 'GMPO_BD_EXMPFREE' | '???'
'2.0K'    | '1%'      | '1/16W' | '0402'    | 'EMPTY'  | 'G21796-001'(!) = 'YES;YES;YES;UNK;OK;VLD'           | 'G21796-001' | 'SMR0402A' | '(SMX0402,SMX0402A,SMX0402B)' | 'NA'     | '1%'    | '1/16W' | 'DISCRETE' | 'RES_D,0402,2.0KOHM,1.00%,1/16W'                        | '0.017 IN' | 'CHIP0402'     | ''          | '1141' | 'http://speed.intel.com:8081/speed/module/pdm/item/pdm_item_detail_direct.asp?item_cde=G21796-001&item_rev=01&url_param=unused' | 'CONDITIONAL' | 'NO'  | '3'   | 'GMPO_BD_EXMPFREE' | '???'
'1.5K'    | '1%'      | '1/16W' | '0402'    | 'EMPTY'  | 'G21796-003'(!) = 'YES;YES;YES;UNK;OK;VLD'           | 'G21796-003' | 'SMR0402A' | '(SMX0402,SMX0402A,SMX0402B)' | 'NA'     | '1%'    | '1/16W' | 'DISCRETE' | 'RES_D,0402,1.5KOHM,1.00%,1/16W'                        | '0.017 IN' | 'CHIP0402'     | ''          | '1141' | 'http://speed.intel.com:8081/speed/module/pdm/item/pdm_item_detail_direct.asp?item_cde=G21796-003&item_rev=01&url_param=unused' | 'DESIGN'      | 'NO'  | '3'   | 'GMPO_BD_EXMPFREE' | '???'
'1.5K'    | '1%'      | '1/16W' | '0402'    | 'CHIP'   | 'G21796-003'(!) = 'YES;YES;YES;UNK;OK;VLD'           | 'G21796-003' | 'SMR0402A' | '(SMX0402,SMX0402A,SMX0402B)' | '1.5K'   | '1%'    | '1/16W' | 'DISCRETE' | 'RES_D,0402,1.5KOHM,1.00%,1/16W'                        | '0.017 IN' | 'CHIP0402'     | ''          | '1141' | 'http://speed.intel.com:8081/speed/module/pdm/item/pdm_item_detail_direct.asp?item_cde=G21796-003&item_rev=01&url_param=unused' | 'DESIGN'      | 'NO'  | '3'   | 'GMPO_BD_EXMPFREE' | '???'
'200.0'   | '1%'      | '1/16W' | '0402'    | 'EMPTY'  | 'G21796-004'(!) = 'YES;YES;YES;UNK;OK;VLD'           | 'G21796-004' | 'SMR0402A' | '(SMX0402,SMX0402A,SMX0402B)' | 'NA'     | '1%'    | '1/16W' | 'DISCRETE' | 'RES_D,0402,200.0OHM,1.00%,1/16W'                       | '0.017 IN' | 'CHIP0402'     | ''          | '1141' | 'http://speed.intel.com:8081/speed/module/pdm/item/pdm_item_detail_direct.asp?item_cde=G21796-004&item_rev=01&url_param=unused' | 'UNQUAL'      | 'NO'  | '3'   | 'GMPO_BD_EXMPFREE' | '???'
'200.0'   | '1%'      | '1/16W' | '0402'    | 'CHIP'   | 'G21796-004'(!) = 'YES;YES;YES;UNK;OK;VLD'           | 'G21796-004' | 'SMR0402A' | '(SMX0402,SMX0402A,SMX0402B)' | '200.0'  | '1%'    | '1/16W' | 'DISCRETE' | 'RES_D,0402,200.0OHM,1.00%,1/16W'                       | '0.017 IN' | 'CHIP0402'     | ''          | '1141' | 'http://speed.intel.com:8081/speed/module/pdm/item/pdm_item_detail_direct.asp?item_cde=G21796-004&item_rev=01&url_param=unused' | 'UNQUAL'      | 'NO'  | '3'   | 'GMPO_BD_EXMPFREE' | '???'
'69.8K'   | '1%'      | '1/16W' | '0402'    | 'EMPTY'  | 'G21796-007'(!) = 'YES;YES;YES;UNK;OK;VLD'           | 'G21796-007' | 'SMR0402A' | '(SMX0402,SMX0402A,SMX0402B)' | 'NA'     | '1%'    | '1/16W' | 'DISCRETE' | 'RES_D,0402,69.8KOHM,1.00%,1/16W'                       | '0.017 IN' | 'CHIP0402'     | ''          | '1141' | 'http://speed.intel.com:8081/speed/module/pdm/item/pdm_item_detail_direct.asp?item_cde=G21796-007&item_rev=01&url_param=unused' | 'DESIGN'      | 'NO'  | '3'   | 'GMPO_BD_EXMPFREE' | '???'
'69.8K'   | '1%'      | '1/16W' | '0402'    | 'CHIP'   | 'G21796-007'(!) = 'YES;YES;YES;UNK;OK;VLD'           | 'G21796-007' | 'SMR0402A' | '(SMX0402,SMX0402A,SMX0402B)' | '69.8K'  | '1%'    | '1/16W' | 'DISCRETE' | 'RES_D,0402,69.8KOHM,1.00%,1/16W'                       | '0.017 IN' | 'CHIP0402'     | ''          | '1141' | 'http://speed.intel.com:8081/speed/module/pdm/item/pdm_item_detail_direct.asp?item_cde=G21796-007&item_rev=01&url_param=unused' | 'DESIGN'      | 'NO'  | '3'   | 'GMPO_BD_EXMPFREE' | '???'
'150.0'   | '1%'      | '1/16W' | '0402'    | 'EMPTY'  | 'G21796-009'(!) = 'YES;YES;YES;UNK;OK;VLD'           | 'G21796-009' | 'SMR0402A' | '(SMX0402,SMX0402A,SMX0402B)' | 'NA'     | '1%'    | '1/16W' | 'DISCRETE' | 'RES_D,0402,150.0OHM,1.00%,1/16W'                       | '0.017 IN' | 'CHIP0402'     | ''          | '1141' | 'http://speed.intel.com:8081/speed/module/pdm/item/pdm_item_detail_direct.asp?item_cde=G21796-009&item_rev=01&url_param=unused' | 'DESIGN'      | 'NO'  | '3'   | 'GMPO_BD_EXMPFREE' | '???'
'150.0'   | '1%'      | '1/16W' | '0402'    | 'CHIP'   | 'G21796-009'(!) = 'YES;YES;YES;UNK;OK;VLD'           | 'G21796-009' | 'SMR0402A' | '(SMX0402,SMX0402A,SMX0402B)' | '150.0'  | '1%'    | '1/16W' | 'DISCRETE' | 'RES_D,0402,150.0OHM,1.00%,1/16W'                       | '0.017 IN' | 'CHIP0402'     | ''          | '1141' | 'http://speed.intel.com:8081/speed/module/pdm/item/pdm_item_detail_direct.asp?item_cde=G21796-009&item_rev=01&url_param=unused' | 'DESIGN'      | 'NO'  | '3'   | 'GMPO_BD_EXMPFREE' | '???'
'100.0K'  | '1%'      | '1/16W' | '0402'    | 'CHIP'   | 'G21796-010'(!) = 'YES;YES;YES;UNK;OK;VLD'           | 'G21796-010' | 'SMR0402A' | '(SMX0402,SMX0402A,SMX0402B)' | '100.0K' | '1%'    | '1/16W' | 'DISCRETE' | 'RES_D,0402,100.0KOHM,1.00%,1/16W'                      | '0.017 IN' | 'CHIP0402'     | ''          | '1141' | 'http://speed.intel.com:8081/speed/module/pdm/item/pdm_item_detail_direct.asp?item_cde=G21796-010&item_rev=01&url_param=unused' | 'UNQUAL'      | 'NO'  | '3'   | 'GMPO_BD_EXMPFREE' | '???'
'100.0K'  | '1%'      | '1/16W' | '0402'    | 'EMPTY'  | 'G21796-010'(!) = 'YES;YES;YES;UNK;OK;VLD'           | 'G21796-010' | 'SMR0402A' | '(SMX0402,SMX0402A,SMX0402B)' | 'NA'     | '1%'    | '1/16W' | 'DISCRETE' | 'RES_D,0402,100.0KOHM,1.00%,1/16W'                      | '0.017 IN' | 'CHIP0402'     | ''          | '1141' | 'http://speed.intel.com:8081/speed/module/pdm/item/pdm_item_detail_direct.asp?item_cde=G21796-010&item_rev=01&url_param=unused' | 'UNQUAL'      | 'NO'  | '3'   | 'GMPO_BD_EXMPFREE' | '???'
'4.99K'   | '1%'      | '1/16W' | '0402'    | 'EMPTY'  | 'G21796-013'(!) = 'YES;YES;YES;UNK;OK;VLD'           | 'G21796-013' | 'SMR0402A' | '(SMX0402,SMX0402A,SMX0402B)' | 'NA'     | '1%'    | '1/16W' | 'DISCRETE' | 'RES_D,0402,4.99KOHM,1.00%,1/16W'                       | '0.017 IN' | 'CHIP0402'     | ''          | '1141' | 'http://speed.intel.com:8081/speed/module/pdm/item/pdm_item_detail_direct.asp?item_cde=G21796-013&item_rev=01&url_param=unused' | 'UNQUAL'      | 'NO'  | '4'   | 'GMPO_BD_EXMPFREE' | '???'
'4.99K'   | '1%'      | '1/16W' | '0402'    | 'CHIP'   | 'G21796-013'(!) = 'YES;YES;YES;UNK;OK;VLD'           | 'G21796-013' | 'SMR0402A' | '(SMX0402,SMX0402A,SMX0402B)' | '4.99K'  | '1%'    | '1/16W' | 'DISCRETE' | 'RES_D,0402,4.99KOHM,1.00%,1/16W'                       | '0.017 IN' | 'CHIP0402'     | ''          | '1141' | 'http://speed.intel.com:8081/speed/module/pdm/item/pdm_item_detail_direct.asp?item_cde=G21796-013&item_rev=01&url_param=unused' | 'UNQUAL'      | 'NO'  | '4'   | 'GMPO_BD_EXMPFREE' | '???'
'10.0K'   | '1%'      | '1/16W' | '0402'    | 'EMPTY'  | 'G21796-016'(!) = 'YES;YES;YES;UNK;OK;VLD'           | 'G21796-016' | 'SMR0402A' | '(SMX0402,SMX0402A,SMX0402B)' | 'NA'     | '1%'    | '1/16W' | 'DISCRETE' | 'RES_D,0402,10.0KOHM,1.00%,1/16W'                       | '0.017 IN' | 'CHIP0402'     | ''          | '1141' | 'http://speed.intel.com:8081/speed/module/pdm/item/pdm_item_detail_direct.asp?item_cde=G21796-016&item_rev=01&url_param=unused' | 'UNQUAL'      | 'NO'  | '3'   | 'GMPO_BD_EXMPFREE' | '???'
'10.0K'   | '1%'      | '1/16W' | '0402'    | 'CHIP'   | 'G21796-016'(!) = 'YES;YES;YES;UNK;OK;VLD'           | 'G21796-016' | 'SMR0402A' | '(SMX0402,SMX0402A,SMX0402B)' | '10.0K'  | '1%'    | '1/16W' | 'DISCRETE' | 'RES_D,0402,10.0KOHM,1.00%,1/16W'                       | '0.017 IN' | 'CHIP0402'     | ''          | '1141' | 'http://speed.intel.com:8081/speed/module/pdm/item/pdm_item_detail_direct.asp?item_cde=G21796-016&item_rev=01&url_param=unused' | 'UNQUAL'      | 'NO'  | '3'   | 'GMPO_BD_EXMPFREE' | '???'
'100.0'   | '1%'      | '1/16W' | '0402'    | 'EMPTY'  | 'G21796-017'(!) = 'YES;YES;YES;UNK;OK;VLD'           | 'G21796-017' | 'SMR0402A' | '(SMX0402,SMX0402A,SMX0402B)' | 'NA'     | '1%'    | '1/16W' | 'DISCRETE' | 'RES_D,0402,100.0OHM,1.00%,1/16W'                       | '0.017 IN' | 'CHIP0402'     | ''          | '1141' | 'http://speed.intel.com:8081/speed/module/pdm/item/pdm_item_detail_direct.asp?item_cde=G21796-017&item_rev=01&url_param=unused' | 'UNQUAL'      | 'NO'  | '4'   | 'GMPO_BD_EXMPFREE' | '???'
'100.0'   | '1%'      | '1/16W' | '0402'    | 'CHIP'   | 'G21796-017'(!) = 'YES;YES;YES;UNK;OK;VLD'           | 'G21796-017' | 'SMR0402A' | '(SMX0402,SMX0402A,SMX0402B)' | '100.0'  | '1%'    | '1/16W' | 'DISCRETE' | 'RES_D,0402,100.0OHM,1.00%,1/16W'                       | '0.017 IN' | 'CHIP0402'     | ''          | '1141' | 'http://speed.intel.com:8081/speed/module/pdm/item/pdm_item_detail_direct.asp?item_cde=G21796-017&item_rev=01&url_param=unused' | 'UNQUAL'      | 'NO'  | '4'   | 'GMPO_BD_EXMPFREE' | '???'
'1.0M'    | '1%'      | '1/16W' | '0402'    | 'CHIP'   | 'G21796-021'(!) = 'YES;YES;YES;UNK;OK;VLD'           | 'G21796-021' | 'SMR0402A' | '(SMX0402,SMX0402A,SMX0402B)' | '1.0M'   | '1%'    | '1/16W' | 'DISCRETE' | 'RES_D,0402,1.0MOHM,1.00%,1/16W'                        | '0.017 IN' | 'CHIP0402'     | ''          | '1141' | 'http://speed.intel.com:8081/speed/module/pdm/item/pdm_item_detail_direct.asp?item_cde=G21796-021&item_rev=01&url_param=unused' | 'DESIGN'      | 'NO'  | '3'   | 'GMPO_BD_EXMPFREE' | '???'
'1.0M'    | '1%'      | '1/16W' | '0402'    | 'EMPTY'  | 'G21796-021'(!) = 'YES;YES;YES;UNK;OK;VLD'           | 'G21796-021' | 'SMR0402A' | '(SMX0402,SMX0402A,SMX0402B)' | 'NA'     | '1%'    | '1/16W' | 'DISCRETE' | 'RES_D,0402,1.0MOHM,1.00%,1/16W'                        | '0.017 IN' | 'CHIP0402'     | ''          | '1141' | 'http://speed.intel.com:8081/speed/module/pdm/item/pdm_item_detail_direct.asp?item_cde=G21796-021&item_rev=01&url_param=unused' | 'DESIGN'      | 'NO'  | '3'   | 'GMPO_BD_EXMPFREE' | '???'
'1.00K'   | '1%'      | '1/16W' | '0402'    | 'CHIP'   | 'G21796-026'(!) = 'YES;YES;YES;UNK;OK;VLD'           | 'G21796-026' | 'SMR0402A' | '(SMX0402,SMX0402A,SMX0402B)' | '1.00K'  | '1%'    | '1/16W' | 'DISCRETE' | 'RES_D,0402,1.00KOHM,1.00%,1/16W'                       | '0.017 IN' | 'CHIP0402'     | ''          | '1141' | 'http://speed.intel.com:8081/speed/module/pdm/item/pdm_item_detail_direct.asp?item_cde=G21796-026&item_rev=01&url_param=unused' | 'UNQUAL'      | 'NO'  | '4'   | 'GMPO_BD_EXMPFREE' | '???'
'1.00K'   | '1%'      | '1/16W' | '0402'    | 'EMPTY'  | 'G21796-026'(!) = 'YES;YES;YES;UNK;OK;VLD'           | 'G21796-026' | 'SMR0402A' | '(SMX0402,SMX0402A,SMX0402B)' | 'NA'     | '1%'    | '1/16W' | 'DISCRETE' | 'RES_D,0402,1.00KOHM,1.00%,1/16W'                       | '0.017 IN' | 'CHIP0402'     | ''          | '1141' | 'http://speed.intel.com:8081/speed/module/pdm/item/pdm_item_detail_direct.asp?item_cde=G21796-026&item_rev=01&url_param=unused' | 'UNQUAL'      | 'NO'  | '4'   | 'GMPO_BD_EXMPFREE' | '???'
'3.32K'   | '1%'      | '1/16W' | '0402'    | 'EMPTY'  | 'G21796-027'(!) = 'YES;YES;YES;UNK;OK;VLD'           | 'G21796-027' | 'SMR0402A' | '(SMX0402,SMX0402A,SMX0402B)' | 'NA'     | '1%'    | '1/16W' | 'DISCRETE' | 'RES_D,0402,3.32KOHM,1.00%,1/16W'                       | '0.017 IN' | 'CHIP0402'     | ''          | '1141' | 'http://speed.intel.com:8081/speed/module/pdm/item/pdm_item_detail_direct.asp?item_cde=G21796-027&item_rev=01&url_param=unused' | 'UNQUAL'      | 'NO'  | '5'   | 'GMPO_BD_EXMPFREE' | '???'
'3.32K'   | '1%'      | '1/16W' | '0402'    | 'CHIP'   | 'G21796-027'(!) = 'YES;YES;YES;UNK;OK;VLD'           | 'G21796-027' | 'SMR0402A' | '(SMX0402,SMX0402A,SMX0402B)' | '3.32K'  | '1%'    | '1/16W' | 'DISCRETE' | 'RES_D,0402,3.32KOHM,1.00%,1/16W'                       | '0.017 IN' | 'CHIP0402'     | ''          | '1141' | 'http://speed.intel.com:8081/speed/module/pdm/item/pdm_item_detail_direct.asp?item_cde=G21796-027&item_rev=01&url_param=unused' | 'UNQUAL'      | 'NO'  | '5'   | 'GMPO_BD_EXMPFREE' | '???'
'20.0K'   | '1%'      | '1/16W' | '0402'    | 'CHIP'   | 'G21796-040'(!) = 'YES;YES;YES;UNK;OK;VLD'           | 'G21796-040' | 'SMR0402A' | '(SMX0402,SMX0402A,SMX0402B)' | '20.0K'  | '1%'    | '1/16W' | 'DISCRETE' | 'RES_D,0402,20.0KOHM,1.00%,1/16W'                       | '0.017 IN' | 'CHIP0402'     | ''          | '1141' | 'http://speed.intel.com:8081/speed/module/pdm/item/pdm_item_detail_direct.asp?item_cde=G21796-040&item_rev=01&url_param=unused' | 'UNQUAL'      | 'NO'  | '4'   | 'GMPO_BD_EXMPFREE' | '???'
'20.0K'   | '1%'      | '1/16W' | '0402'    | 'EMPTY'  | 'G21796-040'(!) = 'YES;YES;YES;UNK;OK;VLD'           | 'G21796-040' | 'SMR0402A' | '(SMX0402,SMX0402A,SMX0402B)' | 'NA'     | '1%'    | '1/16W' | 'DISCRETE' | 'RES_D,0402,20.0KOHM,1.00%,1/16W'                       | '0.017 IN' | 'CHIP0402'     | ''          | '1141' | 'http://speed.intel.com:8081/speed/module/pdm/item/pdm_item_detail_direct.asp?item_cde=G21796-040&item_rev=01&url_param=unused' | 'UNQUAL'      | 'NO'  | '4'   | 'GMPO_BD_EXMPFREE' | '???'
'3.16K'   | '1%'      | '1/16W' | '0402'    | 'EMPTY'  | 'G21796-043'(!) = 'YES;YES;YES;UNK;OK;VLD'           | 'G21796-043' | 'SMR0402A' | '(SMX0402,SMX0402A,SMX0402B)' | 'NA'     | '1%'    | '1/16W' | 'DISCRETE' | 'RES_D,0402,3.16KOHM,1.00%,1/16W'                       | '0.017 IN' | 'CHIP0402'     | ''          | '1141' | 'http://speed.intel.com:8081/speed/module/pdm/item/pdm_item_detail_direct.asp?item_cde=G21796-043&item_rev=01&url_param=unused' | 'DESIGN'      | 'NO'  | '4'   | 'GMPO_BD_EXMPFREE' | '???'
'3.16K'   | '1%'      | '1/16W' | '0402'    | 'CHIP'   | 'G21796-043'(!) = 'YES;YES;YES;UNK;OK;VLD'           | 'G21796-043' | 'SMR0402A' | '(SMX0402,SMX0402A,SMX0402B)' | '3.16K'  | '1%'    | '1/16W' | 'DISCRETE' | 'RES_D,0402,3.16KOHM,1.00%,1/16W'                       | '0.017 IN' | 'CHIP0402'     | ''          | '1141' | 'http://speed.intel.com:8081/speed/module/pdm/item/pdm_item_detail_direct.asp?item_cde=G21796-043&item_rev=01&url_param=unused' | 'DESIGN'      | 'NO'  | '4'   | 'GMPO_BD_EXMPFREE' | '???'
'49.9'    | '1%'      | '1/16W' | '0402'    | 'CHIP'   | 'G21796-047'(!) = 'YES;YES;YES;UNK;OK;VLD'           | 'G21796-047' | 'SMR0402A' | '(SMX0402,SMX0402A,SMX0402B)' | '49.9'   | '1%'    | '1/16W' | 'DISCRETE' | 'RES_D,0402,49.9 OHM,1.00%,1/16W'                       | '0.017 IN' | 'CHIP0402'     | ''          | '1141' | 'http://speed.intel.com:8081/speed/module/pdm/item/pdm_item_detail_direct.asp?item_cde=G21796-047&item_rev=01&url_param=unused' | 'UNQUAL'      | 'NO'  | '4'   | 'GMPO_BD_EXMPFREE' | '???'
'49.9'    | '1%'      | '1/16W' | '0402'    | 'EMPTY'  | 'G21796-047'(!) = 'YES;YES;YES;UNK;OK;VLD'           | 'G21796-047' | 'SMR0402A' | '(SMX0402,SMX0402A,SMX0402B)' | 'NA'     | '1%'    | '1/16W' | 'DISCRETE' | 'RES_D,0402,49.9 OHM,1.00%,1/16W'                       | '0.017 IN' | 'CHIP0402'     | ''          | '1141' | 'http://speed.intel.com:8081/speed/module/pdm/item/pdm_item_detail_direct.asp?item_cde=G21796-047&item_rev=01&url_param=unused' | 'UNQUAL'      | 'NO'  | '4'   | 'GMPO_BD_EXMPFREE' | '???'
'49.9K'   | '1%'      | '1/16W' | '0402'    | 'CHIP'   | 'G21796-048'(!) = 'YES;YES;YES;UNK;OK;VLD'           | 'G21796-048' | 'SMR0402A' | '(SMX0402,SMX0402A,SMX0402B)' | '49.9K'  | '1%'    | '1/16W' | 'DISCRETE' | 'RES_D,0402,49.9KOHM,1.00%,1/16W'                       | '0.017 IN' | 'CHIP0402'     | ''          | '1141' | 'http://speed.intel.com:8081/speed/module/pdm/item/pdm_item_detail_direct.asp?item_cde=G21796-048&item_rev=01&url_param=unused' | 'UNQUAL'      | 'NO'  | '4'   | 'GMPO_BD_EXMPFREE' | '???'
'49.9K'   | '1%'      | '1/16W' | '0402'    | 'EMPTY'  | 'G21796-048'(!) = 'YES;YES;YES;UNK;OK;VLD'           | 'G21796-048' | 'SMR0402A' | '(SMX0402,SMX0402A,SMX0402B)' | 'NA'     | '1%'    | '1/16W' | 'DISCRETE' | 'RES_D,0402,49.9KOHM,1.00%,1/16W'                       | '0.017 IN' | 'CHIP0402'     | ''          | '1141' | 'http://speed.intel.com:8081/speed/module/pdm/item/pdm_item_detail_direct.asp?item_cde=G21796-048&item_rev=01&url_param=unused' | 'UNQUAL'      | 'NO'  | '4'   | 'GMPO_BD_EXMPFREE' | '???'
'90.9K'   | '1%'      | '1/16W' | '0402'    | 'CHIP'   | 'G21796-058'(!) = 'YES;YES;YES;UNK;OK;VLD'           | 'G21796-058' | 'SMR0402A' | '(SMX0402,SMX0402A,SMX0402B)' | '90.9K'  | '1%'    | '1/16W' | 'DISCRETE' | 'RES_D,0402,90.9KOHM,1.00%,1/16W'                       | '0.017 IN' | 'CHIP0402'     | ''          | '1141' | 'http://speed.intel.com:8081/speed/module/pdm/item/pdm_item_detail_direct.asp?item_cde=G21796-058&item_rev=01&url_param=unused' | 'UNQUAL'      | 'NO'  | '4'   | 'GMPO_BD_EXMPFREE' | '???'
'90.9K'   | '1%'      | '1/16W' | '0402'    | 'EMPTY'  | 'G21796-058'(!) = 'YES;YES;YES;UNK;OK;VLD'           | 'G21796-058' | 'SMR0402A' | '(SMX0402,SMX0402A,SMX0402B)' | 'NA'     | '1%'    | '1/16W' | 'DISCRETE' | 'RES_D,0402,90.9KOHM,1.00%,1/16W'                       | '0.017 IN' | 'CHIP0402'     | ''          | '1141' | 'http://speed.intel.com:8081/speed/module/pdm/item/pdm_item_detail_direct.asp?item_cde=G21796-058&item_rev=01&url_param=unused' | 'UNQUAL'      | 'NO'  | '4'   | 'GMPO_BD_EXMPFREE' | '???'
'3.74K'   | '1%'      | '1/16W' | '0402'    | 'EMPTY'  | 'G21796-059'(!) = 'YES;YES;YES;UNK;OK;VLD'           | 'G21796-059' | 'SMR0402A' | '(SMX0402,SMX0402A,SMX0402B)' | 'NA'     | '1%'    | '1/16W' | 'DISCRETE' | 'RES_D,0402,3.74KOHM,1.00%,1/16W'                       | '0.017 IN' | 'CHIP0402'     | ''          | '1141' | 'http://speed.intel.com:8081/speed/module/pdm/item/pdm_item_detail_direct.asp?item_cde=G21796-059&item_rev=01&url_param=unused' | 'DESIGN'      | 'NO'  | '4'   | 'GMPO_BD_EXMPFREE' | '???'
'3.74K'   | '1%'      | '1/16W' | '0402'    | 'CHIP'   | 'G21796-059'(!) = 'YES;YES;YES;UNK;OK;VLD'           | 'G21796-059' | 'SMR0402A' | '(SMX0402,SMX0402A,SMX0402B)' | '3.74K'  | '1%'    | '1/16W' | 'DISCRETE' | 'RES_D,0402,3.74KOHM,1.00%,1/16W'                       | '0.017 IN' | 'CHIP0402'     | ''          | '1141' | 'http://speed.intel.com:8081/speed/module/pdm/item/pdm_item_detail_direct.asp?item_cde=G21796-059&item_rev=01&url_param=unused' | 'DESIGN'      | 'NO'  | '4'   | 'GMPO_BD_EXMPFREE' | '???'
'10.0'    | '1%'      | '1/16W' | '0402'    | 'EMPTY'  | 'G21796-066'(!) = 'YES;YES;YES;UNK;OK;VLD'           | 'G21796-066' | 'SMR0402A' | '(SMX0402,SMX0402A,SMX0402B)' | 'NA'     | '1%'    | '1/16W' | 'DISCRETE' | 'RES_D,0402,10.0OHM,1.00%,1/16W'                        | '0.017 IN' | 'CHIP0402'     | ''          | '1141' | 'http://speed.intel.com:8081/speed/module/pdm/item/pdm_item_detail_direct.asp?item_cde=G21796-066&item_rev=01&url_param=unused' | 'UNQUAL'      | 'NO'  | '3'   | 'GMPO_BD_EXMPFREE' | '???'
'10.0'    | '1%'      | '1/16W' | '0402'    | 'CHIP'   | 'G21796-066'(!) = 'YES;YES;YES;UNK;OK;VLD'           | 'G21796-066' | 'SMR0402A' | '(SMX0402,SMX0402A,SMX0402B)' | '10.0'   | '1%'    | '1/16W' | 'DISCRETE' | 'RES_D,0402,10.0OHM,1.00%,1/16W'                        | '0.017 IN' | 'CHIP0402'     | ''          | '1141' | 'http://speed.intel.com:8081/speed/module/pdm/item/pdm_item_detail_direct.asp?item_cde=G21796-066&item_rev=01&url_param=unused' | 'UNQUAL'      | 'NO'  | '3'   | 'GMPO_BD_EXMPFREE' | '???'
'4.75K'   | '1%'      | '1/16W' | '0402'    | 'EMPTY'  | 'G21796-072'(!) = 'YES;YES;YES;UNK;OK;VLD'           | 'G21796-072' | 'SMR0402A' | '(SMX0402,SMX0402A,SMX0402B)' | 'NA'     | '1%'    | '1/16W' | 'DISCRETE' | 'RES_D,0402,4.75KOHM,1.00%,1/16W'                       | '0.017 IN' | 'CHIP0402'     | ''          | '1141' | 'http://speed.intel.com:8081/speed/module/pdm/item/pdm_item_detail_direct.asp?item_cde=G21796-072&item_rev=01&url_param=unused' | 'UNQUAL'      | 'NO'  | '3'   | 'GMPO_BD_EXMPFREE' | '???'
'4.75K'   | '1%'      | '1/16W' | '0402'    | 'CHIP'   | 'G21796-072'(!) = 'YES;YES;YES;UNK;OK;VLD'           | 'G21796-072' | 'SMR0402A' | '(SMX0402,SMX0402A,SMX0402B)' | '4.75K'  | '1%'    | '1/16W' | 'DISCRETE' | 'RES_D,0402,4.75KOHM,1.00%,1/16W'                       | '0.017 IN' | 'CHIP0402'     | ''          | '1141' | 'http://speed.intel.com:8081/speed/module/pdm/item/pdm_item_detail_direct.asp?item_cde=G21796-072&item_rev=01&url_param=unused' | 'UNQUAL'      | 'NO'  | '3'   | 'GMPO_BD_EXMPFREE' | '???'
'33.2'    | '1%'      | '1/16W' | '0402'    | 'EMPTY'  | 'G21796-074'(!) = 'YES;YES;YES;UNK;OK;VLD'           | 'G21796-074' | 'SMR0402A' | '(SMX0402,SMX0402A,SMX0402B)' | 'NA'     | '1%'    | '1/16W' | 'DISCRETE' | 'RES_D,0402,33.2OHM,1.00%,1/16W'                        | '0.017 IN' | 'CHIP0402'     | ''          | '1141' | 'http://speed.intel.com:8081/speed/module/pdm/item/pdm_item_detail_direct.asp?item_cde=G21796-074&item_rev=01&url_param=unused' | 'UNQUAL'      | 'NO'  | '3'   | 'GMPO_BD_EXMPFREE' | '???'
'33.2'    | '1%'      | '1/16W' | '0402'    | 'CHIP'   | 'G21796-074'(!) = 'YES;YES;YES;UNK;OK;VLD'           | 'G21796-074' | 'SMR0402A' | '(SMX0402,SMX0402A,SMX0402B)' | '33.2'   | '1%'    | '1/16W' | 'DISCRETE' | 'RES_D,0402,33.2OHM,1.00%,1/16W'                        | '0.017 IN' | 'CHIP0402'     | ''          | '1141' | 'http://speed.intel.com:8081/speed/module/pdm/item/pdm_item_detail_direct.asp?item_cde=G21796-074&item_rev=01&url_param=unused' | 'UNQUAL'      | 'NO'  | '3'   | 'GMPO_BD_EXMPFREE' | '???'
'301.0'   | '1%'      | '1/16W' | '0402'    | 'EMPTY'  | 'G21796-076'(!) = 'YES;YES;YES;UNK;OK;VLD'           | 'G21796-076' | 'SMR0402A' | '(SMX0402,SMX0402A,SMX0402B)' | 'NA'     | '1%'    | '1/16W' | 'DISCRETE' | 'RES_D,0402,301.0OHM,1.00%,1/16W'                       | '0.017 IN' | 'CHIP0402'     | ''          | '1141' | 'http://speed.intel.com:8081/speed/module/pdm/item/pdm_item_detail_direct.asp?item_cde=G21796-076&item_rev=01&url_param=unused' | 'UNQUAL'      | 'NO'  | '3'   | 'GMPO_BD_EXMPFREE' | '???'
'301.0'   | '1%'      | '1/16W' | '0402'    | 'CHIP'   | 'G21796-076'(!) = 'YES;YES;YES;UNK;OK;VLD'           | 'G21796-076' | 'SMR0402A' | '(SMX0402,SMX0402A,SMX0402B)' | '301.0'  | '1%'    | '1/16W' | 'DISCRETE' | 'RES_D,0402,301.0OHM,1.00%,1/16W'                       | '0.017 IN' | 'CHIP0402'     | ''          | '1141' | 'http://speed.intel.com:8081/speed/module/pdm/item/pdm_item_detail_direct.asp?item_cde=G21796-076&item_rev=01&url_param=unused' | 'UNQUAL'      | 'NO'  | '3'   | 'GMPO_BD_EXMPFREE' | '???'
'475.0'   | '1%'      | '1/16W' | '0402'    | 'CHIP'   | 'G21796-077'(!) = 'YES;YES;YES;UNK;OK;VLD'           | 'G21796-077' | 'SMR0402A' | '(SMX0402,SMX0402A,SMX0402B)' | '475.0'  | '1%'    | '1/16W' | 'DISCRETE' | 'RES_D,0402,475.0OHM,1.00%,1/16W'                       | '0.017 IN' | 'CHIP0402'     | ''          | '1141' | 'http://speed.intel.com:8081/speed/module/pdm/item/pdm_item_detail_direct.asp?item_cde=G21796-077&item_rev=01&url_param=unused' | 'UNQUAL'      | 'NO'  | '3'   | 'GMPO_BD_EXMPFREE' | '???'
'475.0'   | '1%'      | '1/16W' | '0402'    | 'EMPTY'  | 'G21796-077'(!) = 'YES;YES;YES;UNK;OK;VLD'           | 'G21796-077' | 'SMR0402A' | '(SMX0402,SMX0402A,SMX0402B)' | 'NA'     | '1%'    | '1/16W' | 'DISCRETE' | 'RES_D,0402,475.0OHM,1.00%,1/16W'                       | '0.017 IN' | 'CHIP0402'     | ''          | '1141' | 'http://speed.intel.com:8081/speed/module/pdm/item/pdm_item_detail_direct.asp?item_cde=G21796-077&item_rev=01&url_param=unused' | 'UNQUAL'      | 'NO'  | '3'   | 'GMPO_BD_EXMPFREE' | '???'
'8.06K'   | '1%'      | '1/16W' | '0402'    | 'EMPTY'  | 'G21796-078'(!) = 'YES;YES;YES;UNK;OK;VLD'           | 'G21796-078' | 'SMR0402A' | '(SMX0402,SMX0402A,SMX0402B)' | 'NA'     | '1%'    | '1/16W' | 'DISCRETE' | 'RES_D,0402,8.06KOHM,1.00%,1/16W'                       | '0.017 IN' | 'CHIP0402'     | ''          | '1141' | 'http://speed.intel.com:8081/speed/module/pdm/item/pdm_item_detail_direct.asp?item_cde=G21796-078&item_rev=01&url_param=unused' | 'UNQUAL'      | 'NO'  | '3'   | 'GMPO_BD_EXMPFREE' | '???'
'8.06K'   | '1%'      | '1/16W' | '0402'    | 'CHIP'   | 'G21796-078'(!) = 'YES;YES;YES;UNK;OK;VLD'           | 'G21796-078' | 'SMR0402A' | '(SMX0402,SMX0402A,SMX0402B)' | '8.06K'  | '1%'    | '1/16W' | 'DISCRETE' | 'RES_D,0402,8.06KOHM,1.00%,1/16W'                       | '0.017 IN' | 'CHIP0402'     | ''          | '1141' | 'http://speed.intel.com:8081/speed/module/pdm/item/pdm_item_detail_direct.asp?item_cde=G21796-078&item_rev=01&url_param=unused' | 'UNQUAL'      | 'NO'  | '3'   | 'GMPO_BD_EXMPFREE' | '???'
'200.0K'  | '1%'      | '1/16W' | '0402'    | 'CHIP'   | 'G21796-080'(!) = 'YES;YES;YES;UNK;OK;VLD'           | 'G21796-080' | 'SMR0402A' | '(SMX0402,SMX0402A,SMX0402B)' | '200.0K' | '1%'    | '1/16W' | 'DISCRETE' | 'RES_D,0402,200.0KOHM,1.00%,1/16W'                      | '0.017 IN' | 'CHIP0402'     | ''          | '1141' | 'http://speed.intel.com:8081/speed/module/pdm/item/pdm_item_detail_direct.asp?item_cde=G21796-080&item_rev=01&url_param=unused' | 'UNQUAL'      | 'NO'  | '3'   | 'GMPO_BD_EXMPFREE' | '???'
'200.0K'  | '1%'      | '1/16W' | '0402'    | 'EMPTY'  | 'G21796-080'(!) = 'YES;YES;YES;UNK;OK;VLD'           | 'G21796-080' | 'SMR0402A' | '(SMX0402,SMX0402A,SMX0402B)' | 'NA'     | '1%'    | '1/16W' | 'DISCRETE' | 'RES_D,0402,200.0KOHM,1.00%,1/16W'                      | '0.017 IN' | 'CHIP0402'     | ''          | '1141' | 'http://speed.intel.com:8081/speed/module/pdm/item/pdm_item_detail_direct.asp?item_cde=G21796-080&item_rev=01&url_param=unused' | 'UNQUAL'      | 'NO'  | '3'   | 'GMPO_BD_EXMPFREE' | '???'
'4.02K'   | '1%'      | '1/16W' | '0402'    | 'CHIP'   | 'G21796-082'(!) = 'YES;YES;YES;UNK;OK;VLD'           | 'G21796-082' | 'SMR0402A' | '(SMX0402,SMX0402A,SMX0402B)' | '4.02K'  | '1%'    | '1/16W' | 'DISCRETE' | 'RES_D,0402,4.02KOHM,1.00%,1/16W'                       | '0.017 IN' | 'CHIP0402'     | ''          | '1141' | 'http://speed.intel.com:8081/speed/module/pdm/item/pdm_item_detail_direct.asp?item_cde=G21796-082&item_rev=01&url_param=unused' | 'UNQUAL'      | 'NO'  | '3'   | 'GMPO_BD_EXMPFREE' | '???'
'4.02K'   | '1%'      | '1/16W' | '0402'    | 'EMPTY'  | 'G21796-082'(!) = 'YES;YES;YES;UNK;OK;VLD'           | 'G21796-082' | 'SMR0402A' | '(SMX0402,SMX0402A,SMX0402B)' | 'NA'     | '1%'    | '1/16W' | 'DISCRETE' | 'RES_D,0402,4.02KOHM,1.00%,1/16W'                       | '0.017 IN' | 'CHIP0402'     | ''          | '1141' | 'http://speed.intel.com:8081/speed/module/pdm/item/pdm_item_detail_direct.asp?item_cde=G21796-082&item_rev=01&url_param=unused' | 'UNQUAL'      | 'NO'  | '3'   | 'GMPO_BD_EXMPFREE' | '???'
'12.1K'   | '1%'      | '1/16W' | '0402'    | 'CHIP'   | 'G21796-089'(!) = 'YES;YES;YES;UNK;OK;VLD'           | 'G21796-089' | 'SMR0402A' | '(SMX0402,SMX0402A,SMX0402B)' | '12.1K'  | '1%'    | '1/16W' | 'DISCRETE' | 'RES_D,0402,12.1KOHM,1.00%,1/16W'                       | '0.017 IN' | 'CHIP0402'     | ''          | '1141' | 'http://speed.intel.com:8081/speed/module/pdm/item/pdm_item_detail_direct.asp?item_cde=G21796-089&item_rev=01&url_param=unused' | 'UNQUAL'      | 'NO'  | '3'   | 'GMPO_BD_EXMPFREE' | '???'
'12.1K'   | '1%'      | '1/16W' | '0402'    | 'EMPTY'  | 'G21796-089'(!) = 'YES;YES;YES;UNK;OK;VLD'           | 'G21796-089' | 'SMR0402A' | '(SMX0402,SMX0402A,SMX0402B)' | 'NA'     | '1%'    | '1/16W' | 'DISCRETE' | 'RES_D,0402,12.1KOHM,1.00%,1/16W'                       | '0.017 IN' | 'CHIP0402'     | ''          | '1141' | 'http://speed.intel.com:8081/speed/module/pdm/item/pdm_item_detail_direct.asp?item_cde=G21796-089&item_rev=01&url_param=unused' | 'UNQUAL'      | 'NO'  | '3'   | 'GMPO_BD_EXMPFREE' | '???'
'1.0'     | '1%'      | '1/16W' | '0402'    | 'CHIP'   | 'G21796-090'(!) = 'YES;YES;YES;UNK;OK;VLD'           | 'G21796-090' | 'SMR0402A' | '(SMX0402,SMX0402A,SMX0402B)' | '1.0'    | '1%'    | '1/16W' | 'DISCRETE' | 'RES_D,0402,1.00OHM,1.00%,1/16W'                        | '0.017 IN' | 'CHIP0402'     | ''          | '1141' | 'http://speed.intel.com:8081/speed/module/pdm/item/pdm_item_detail_direct.asp?item_cde=G21796-090&item_rev=01&url_param=unused' | 'UNQUAL'      | 'NO'  | '2'   | 'GMPO_BD_EXMPFREE' | '???'
'1.0'     | '1%'      | '1/16W' | '0402'    | 'EMPTY'  | 'G21796-090'(!) = 'YES;YES;YES;UNK;OK;VLD'           | 'G21796-090' | 'SMR0402A' | '(SMX0402,SMX0402A,SMX0402B)' | 'NA'     | '1%'    | '1/16W' | 'DISCRETE' | 'RES_D,0402,1.00OHM,1.00%,1/16W'                        | '0.017 IN' | 'CHIP0402'     | ''          | '1141' | 'http://speed.intel.com:8081/speed/module/pdm/item/pdm_item_detail_direct.asp?item_cde=G21796-090&item_rev=01&url_param=unused' | 'UNQUAL'      | 'NO'  | '2'   | 'GMPO_BD_EXMPFREE' | '???'
'1.37K'   | '1%'      | '1/16W' | '0402'    | 'CHIP'   | 'G21796-095'(!) = 'YES;YES;YES;UNK;OK;VLD'           | 'G21796-095' | 'SMR0402A' | '(SMX0402,SMX0402A,SMX0402B)' | '1.37K'  | '1%'    | '1/16W' | 'DISCRETE' | 'RES_D,0402,1.37KOHM,1.00%,1/16W'                       | '0.017 IN' | 'CHIP0402'     | ''          | '1141' | 'http://speed.intel.com:8081/speed/module/pdm/item/pdm_item_detail_direct.asp?item_cde=G21796-095&item_rev=01&url_param=unused' | 'DESIGN'      | 'NO'  | '3'   | 'GMPO_BD_EXMPFREE' | '???'
'1.37K'   | '1%'      | '1/16W' | '0402'    | 'EMPTY'  | 'G21796-095'(!) = 'YES;YES;YES;UNK;OK;VLD'           | 'G21796-095' | 'SMR0402A' | '(SMX0402,SMX0402A,SMX0402B)' | 'NA'     | '1%'    | '1/16W' | 'DISCRETE' | 'RES_D,0402,1.37KOHM,1.00%,1/16W'                       | '0.017 IN' | 'CHIP0402'     | ''          | '1141' | 'http://speed.intel.com:8081/speed/module/pdm/item/pdm_item_detail_direct.asp?item_cde=G21796-095&item_rev=01&url_param=unused' | 'DESIGN'      | 'NO'  | '3'   | 'GMPO_BD_EXMPFREE' | '???'
'105.0K'  | '1%'      | '1/16W' | '0402'    | 'EMPTY'  | 'G21796-099'(!) = 'YES;YES;YES;UNK;OK;VLD'           | 'G21796-099' | 'SMR0402A' | '(SMX0402,SMX0402A,SMX0402B)' | 'NA'     | '1%'    | '1/16W' | 'DISCRETE' | 'RES_D,0402,105.0KOHM,1.00%,1/16W'                      | '0.017 IN' | 'CHIP0402'     | ''          | '1141' | 'http://speed.intel.com:8081/speed/module/pdm/item/pdm_item_detail_direct.asp?item_cde=G21796-099&item_rev=01&url_param=unused' | 'DESIGN'      | 'NO'  | '3'   | 'GMPO_BD_EXMPFREE' | '???'
'105.0K'  | '1%'      | '1/16W' | '0402'    | 'CHIP'   | 'G21796-099'(!) = 'YES;YES;YES;UNK;OK;VLD'           | 'G21796-099' | 'SMR0402A' | '(SMX0402,SMX0402A,SMX0402B)' | '105.0K' | '1%'    | '1/16W' | 'DISCRETE' | 'RES_D,0402,105.0KOHM,1.00%,1/16W'                      | '0.017 IN' | 'CHIP0402'     | ''          | '1141' | 'http://speed.intel.com:8081/speed/module/pdm/item/pdm_item_detail_direct.asp?item_cde=G21796-099&item_rev=01&url_param=unused' | 'DESIGN'      | 'NO'  | '3'   | 'GMPO_BD_EXMPFREE' | '???'
'15.0K'   | '1%'      | '1/16W' | '0402'    | 'CHIP'   | 'G21796-107'(!) = 'YES;YES;YES;UNK;OK;VLD'           | 'G21796-107' | 'SMR0402A' | '(SMX0402,SMX0402A,SMX0402B)' | '15.0K'  | '1%'    | '1/16W' | 'DISCRETE' | 'RES_D,0402,15.0KOHM,1.00%,1/16W'                       | '0.017 IN' | 'CHIP0402'     | ''          | '1141' | 'http://speed.intel.com:8081/speed/module/pdm/item/pdm_item_detail_direct.asp?item_cde=G21796-107&item_rev=01&url_param=unused' | 'UNQUAL'      | 'NO'  | '3'   | 'GMPO_BD_EXMPFREE' | '???'
'15.0K'   | '1%'      | '1/16W' | '0402'    | 'EMPTY'  | 'G21796-107'(!) = 'YES;YES;YES;UNK;OK;VLD'           | 'G21796-107' | 'SMR0402A' | '(SMX0402,SMX0402A,SMX0402B)' | 'NA'     | '1%'    | '1/16W' | 'DISCRETE' | 'RES_D,0402,15.0KOHM,1.00%,1/16W'                       | '0.017 IN' | 'CHIP0402'     | ''          | '1141' | 'http://speed.intel.com:8081/speed/module/pdm/item/pdm_item_detail_direct.asp?item_cde=G21796-107&item_rev=01&url_param=unused' | 'UNQUAL'      | 'NO'  | '3'   | 'GMPO_BD_EXMPFREE' | '???'
'150.0K'  | '1%'      | '1/16W' | '0402'    | 'EMPTY'  | 'G21796-109'(!) = 'YES;YES;YES;UNK;OK;VLD'           | 'G21796-109' | 'SMR0402A' | '(SMX0402,SMX0402A,SMX0402B)' | 'NA'     | '1%'    | '1/16W' | 'DISCRETE' | 'RES_D,0402,150.0KOHM,1.00%,1/16W'                      | '0.017 IN' | 'CHIP0402'     | ''          | '1141' | 'http://speed.intel.com:8081/speed/module/pdm/item/pdm_item_detail_direct.asp?item_cde=G21796-109&item_rev=01&url_param=unused' | 'UNQUAL'      | 'NO'  | '3'   | 'GMPO_BD_EXMPFREE' | '???'
'150.0K'  | '1%'      | '1/16W' | '0402'    | 'CHIP'   | 'G21796-109'(!) = 'YES;YES;YES;UNK;OK;VLD'           | 'G21796-109' | 'SMR0402A' | '(SMX0402,SMX0402A,SMX0402B)' | '150.0K' | '1%'    | '1/16W' | 'DISCRETE' | 'RES_D,0402,150.0KOHM,1.00%,1/16W'                      | '0.017 IN' | 'CHIP0402'     | ''          | '1141' | 'http://speed.intel.com:8081/speed/module/pdm/item/pdm_item_detail_direct.asp?item_cde=G21796-109&item_rev=01&url_param=unused' | 'UNQUAL'      | 'NO'  | '3'   | 'GMPO_BD_EXMPFREE' | '???'
'2.21K'   | '1%'      | '1/16W' | '0402'    | 'CHIP'   | 'G21796-112'(!) = 'YES;YES;YES;UNK;OK;VLD'           | 'G21796-112' | 'SMR0402A' | '(SMX0402,SMX0402A,SMX0402B)' | '2.21K'  | '1%'    | '1/16W' | 'DISCRETE' | 'RES_D,0402,2.21KOHM,1.00%,1/16W'                       | '0.017 IN' | 'CHIP0402'     | ''          | '1141' | 'http://speed.intel.com:8081/speed/module/pdm/item/pdm_item_detail_direct.asp?item_cde=G21796-112&item_rev=01&url_param=unused' | 'DESIGN'      | 'NO'  | '3'   | 'GMPO_BD_EXMPFREE' | '???'
'2.21K'   | '1%'      | '1/16W' | '0402'    | 'EMPTY'  | 'G21796-112'(!) = 'YES;YES;YES;UNK;OK;VLD'           | 'G21796-112' | 'SMR0402A' | '(SMX0402,SMX0402A,SMX0402B)' | 'NA'     | '1%'    | '1/16W' | 'DISCRETE' | 'RES_D,0402,2.21KOHM,1.00%,1/16W'                       | '0.017 IN' | 'CHIP0402'     | ''          | '1141' | 'http://speed.intel.com:8081/speed/module/pdm/item/pdm_item_detail_direct.asp?item_cde=G21796-112&item_rev=01&url_param=unused' | 'DESIGN'      | 'NO'  | '3'   | 'GMPO_BD_EXMPFREE' | '???'
'23.2K'   | '1%'      | '1/16W' | '0402'    | 'CHIP'   | 'G21796-114'(!) = 'YES;YES;YES;UNK;OK;VLD'           | 'G21796-114' | 'SMR0402A' | '(SMX0402,SMX0402A,SMX0402B)' | '23.2K'  | '1%'    | '1/16W' | 'DISCRETE' | 'RES_D,0402,23.2KOHM,1.00%,1/16W'                       | '0.017 IN' | 'CHIP0402'     | ''          | '1141' | 'http://speed.intel.com:8081/speed/module/pdm/item/pdm_item_detail_direct.asp?item_cde=G21796-114&item_rev=01&url_param=unused' | 'DESIGN'      | 'NO'  | '3'   | 'GMPO_BD_EXMPFREE' | '???'
'23.2K'   | '1%'      | '1/16W' | '0402'    | 'EMPTY'  | 'G21796-114'(!) = 'YES;YES;YES;UNK;OK;VLD'           | 'G21796-114' | 'SMR0402A' | '(SMX0402,SMX0402A,SMX0402B)' | 'NA'     | '1%'    | '1/16W' | 'DISCRETE' | 'RES_D,0402,23.2KOHM,1.00%,1/16W'                       | '0.017 IN' | 'CHIP0402'     | ''          | '1141' | 'http://speed.intel.com:8081/speed/module/pdm/item/pdm_item_detail_direct.asp?item_cde=G21796-114&item_rev=01&url_param=unused' | 'DESIGN'      | 'NO'  | '3'   | 'GMPO_BD_EXMPFREE' | '???'
'40.2K'   | '1%'      | '1/16W' | '0402'    | 'EMPTY'  | 'G21796-133'(!) = 'YES;YES;YES;UNK;OK;VLD'           | 'G21796-133' | 'SMR0402A' | '(SMX0402,SMX0402A,SMX0402B)' | 'NA'     | '1%'    | '1/16W' | 'DISCRETE' | 'RES_D,0402,40.2KOHM,1.00%,1/16W'                       | '0.017 IN' | 'CHIP0402'     | ''          | '1141' | 'http://speed.intel.com:8081/speed/module/pdm/item/pdm_item_detail_direct.asp?item_cde=G21796-133&item_rev=01&url_param=unused' | 'DESIGN'      | 'NO'  | '3'   | 'GMPO_BD_EXMPFREE' | '???'
'40.2K'   | '1%'      | '1/16W' | '0402'    | 'CHIP'   | 'G21796-133'(!) = 'YES;YES;YES;UNK;OK;VLD'           | 'G21796-133' | 'SMR0402A' | '(SMX0402,SMX0402A,SMX0402B)' | '40.2K'  | '1%'    | '1/16W' | 'DISCRETE' | 'RES_D,0402,40.2KOHM,1.00%,1/16W'                       | '0.017 IN' | 'CHIP0402'     | ''          | '1141' | 'http://speed.intel.com:8081/speed/module/pdm/item/pdm_item_detail_direct.asp?item_cde=G21796-133&item_rev=01&url_param=unused' | 'DESIGN'      | 'NO'  | '3'   | 'GMPO_BD_EXMPFREE' | '???'
'5.11K'   | '1%'      | '1/16W' | '0402'    | 'CHIP'   | 'G21796-140'(!) = 'YES;YES;YES;UNK;OK;VLD'           | 'G21796-140' | 'SMR0402A' | '(SMX0402,SMX0402A,SMX0402B)' | '5.11K'  | '1%'    | '1/16W' | 'DISCRETE' | 'RES_D,0402,5.11KOHM,1.00%,1/16W'                       | '0.017 IN' | 'CHIP0402'     | ''          | '1141' | 'http://speed.intel.com:8081/speed/module/pdm/item/pdm_item_detail_direct.asp?item_cde=G21796-140&item_rev=01&url_param=unused' | 'UNQUAL'      | 'NO'  | '3'   | 'GMPO_BD_EXMPFREE' | '???'
'5.11K'   | '1%'      | '1/16W' | '0402'    | 'EMPTY'  | 'G21796-140'(!) = 'YES;YES;YES;UNK;OK;VLD'           | 'G21796-140' | 'SMR0402A' | '(SMX0402,SMX0402A,SMX0402B)' | 'NA'     | '1%'    | '1/16W' | 'DISCRETE' | 'RES_D,0402,5.11KOHM,1.00%,1/16W'                       | '0.017 IN' | 'CHIP0402'     | ''          | '1141' | 'http://speed.intel.com:8081/speed/module/pdm/item/pdm_item_detail_direct.asp?item_cde=G21796-140&item_rev=01&url_param=unused' | 'UNQUAL'      | 'NO'  | '3'   | 'GMPO_BD_EXMPFREE' | '???'
'5.76K'   | '1%'      | '1/16W' | '0402'    | 'EMPTY'  | 'G21796-143'(!) = 'YES;YES;YES;UNK;OK;VLD'           | 'G21796-143' | 'SMR0402A' | '(SMX0402,SMX0402A,SMX0402B)' | 'NA'     | '1%'    | '1/16W' | 'DISCRETE' | 'RES_D,0402,5.76KOHM,1.00%,1/16W'                       | '0.017 IN' | 'CHIP0402'     | ''          | '1141' | 'http://speed.intel.com:8081/speed/module/pdm/item/pdm_item_detail_direct.asp?item_cde=G21796-143&item_rev=01&url_param=unused' | 'DESIGN'      | 'NO'  | '3'   | 'GMPO_BD_EXMPFREE' | '???'
'5.76K'   | '1%'      | '1/16W' | '0402'    | 'CHIP'   | 'G21796-143'(!) = 'YES;YES;YES;UNK;OK;VLD'           | 'G21796-143' | 'SMR0402A' | '(SMX0402,SMX0402A,SMX0402B)' | '5.76K'  | '1%'    | '1/16W' | 'DISCRETE' | 'RES_D,0402,5.76KOHM,1.00%,1/16W'                       | '0.017 IN' | 'CHIP0402'     | ''          | '1141' | 'http://speed.intel.com:8081/speed/module/pdm/item/pdm_item_detail_direct.asp?item_cde=G21796-143&item_rev=01&url_param=unused' | 'DESIGN'      | 'NO'  | '3'   | 'GMPO_BD_EXMPFREE' | '???'
'6.34K'   | '1%'      | '1/16W' | '0402'    | 'CHIP'   | 'G21796-146'(!) = 'YES;YES;YES;UNK;OK;VLD'           | 'G21796-146' | 'SMR0402A' | '(SMX0402,SMX0402A,SMX0402B)' | '6.34K'  | '1%'    | '1/16W' | 'DISCRETE' | 'RES_D,0402,6.34KOHM,1.00%,1/16W'                       | '0.017 IN' | 'CHIP0402'     | ''          | '1141' | 'http://speed.intel.com:8081/speed/module/pdm/item/pdm_item_detail_direct.asp?item_cde=G21796-146&item_rev=01&url_param=unused' | 'DESIGN'      | 'NO'  | '3'   | 'GMPO_BD_EXMPFREE' | '???'
'6.34K'   | '1%'      | '1/16W' | '0402'    | 'EMPTY'  | 'G21796-146'(!) = 'YES;YES;YES;UNK;OK;VLD'           | 'G21796-146' | 'SMR0402A' | '(SMX0402,SMX0402A,SMX0402B)' | 'NA'     | '1%'    | '1/16W' | 'DISCRETE' | 'RES_D,0402,6.34KOHM,1.00%,1/16W'                       | '0.017 IN' | 'CHIP0402'     | ''          | '1141' | 'http://speed.intel.com:8081/speed/module/pdm/item/pdm_item_detail_direct.asp?item_cde=G21796-146&item_rev=01&url_param=unused' | 'DESIGN'      | 'NO'  | '3'   | 'GMPO_BD_EXMPFREE' | '???'
'64.9K'   | '1%'      | '1/16W' | '0402'    | 'EMPTY'  | 'G21796-148'(!) = 'YES;YES;YES;UNK;OK;VLD'           | 'G21796-148' | 'SMR0402A' | '(SMX0402,SMX0402A,SMX0402B)' | 'NA'     | '1%'    | '1/16W' | 'DISCRETE' | 'RES_D,0402,64.9KOHM,1.00%,1/16W'                       | '0.017 IN' | 'CHIP0402'     | ''          | '1141' | 'http://speed.intel.com:8081/speed/module/pdm/item/pdm_item_detail_direct.asp?item_cde=G21796-148&item_rev=01&url_param=unused' | 'DESIGN'      | 'NO'  | '3'   | 'GMPO_BD_EXMPFREE' | '???'
'64.9K'   | '1%'      | '1/16W' | '0402'    | 'CHIP'   | 'G21796-148'(!) = 'YES;YES;YES;UNK;OK;VLD'           | 'G21796-148' | 'SMR0402A' | '(SMX0402,SMX0402A,SMX0402B)' | '64.9K'  | '1%'    | '1/16W' | 'DISCRETE' | 'RES_D,0402,64.9KOHM,1.00%,1/16W'                       | '0.017 IN' | 'CHIP0402'     | ''          | '1141' | 'http://speed.intel.com:8081/speed/module/pdm/item/pdm_item_detail_direct.asp?item_cde=G21796-148&item_rev=01&url_param=unused' | 'DESIGN'      | 'NO'  | '3'   | 'GMPO_BD_EXMPFREE' | '???'
'100.0K'  | '1%'      | '1/16W' | '0402'    | 'CHIP'   | 'G21796-160'(!) = 'YES;YES;YES;UNK;OK;VLD'           | 'G21796-160' | 'SMR0402A' | '(SMX0402,SMX0402A,SMX0402B)' | '100.0K' | '1%'    | '1/16W' | 'DISCRETE' | 'RES_D,0402,100.0KOHM,1.00%,1/16W'                      | '0.017 IN' | 'CHIP0402'     | ''          | '1141' | 'http://speed.intel.com:8081/speed/module/pdm/item/pdm_item_detail_direct.asp?item_cde=G21796-160&item_rev=01&url_param=unused' | 'DESIGN'      | 'NO'  | '1'   | 'GMPO_BD_EXMPFREE' | '???'
'100.0K'  | '1%'      | '1/16W' | '0402'    | 'EMPTY'  | 'G21796-160'(!) = 'YES;YES;YES;UNK;OK;VLD'           | 'G21796-160' | 'SMR0402A' | '(SMX0402,SMX0402A,SMX0402B)' | 'NA'     | '1%'    | '1/16W' | 'DISCRETE' | 'RES_D,0402,100.0KOHM,1.00%,1/16W'                      | '0.017 IN' | 'CHIP0402'     | ''          | '1141' | 'http://speed.intel.com:8081/speed/module/pdm/item/pdm_item_detail_direct.asp?item_cde=G21796-160&item_rev=01&url_param=unused' | 'DESIGN'      | 'NO'  | '1'   | 'GMPO_BD_EXMPFREE' | '???'
'6.19K'   | '1%'      | '1/16W' | '0402'    | 'CHIP'   | 'G21796-161'(!) = 'YES;YES;YES;UNK;OK;VLD'           | 'G21796-161' | 'SMR0402A' | '(SMX0402,SMX0402A,SMX0402B)' | '6.19K'  | '1%'    | '1/16W' | 'DISCRETE' | 'RES_D,0402,6.19KOHM,1.00%,1/16W'                       | '0.017 IN' | 'CHIP0402'     | ''          | '1141' | 'http://speed.intel.com:8081/speed/module/pdm/item/pdm_item_detail_direct.asp?item_cde=G21796-161&item_rev=01&url_param=unused' | 'UNQUAL'      | 'NO'  | '3'   | 'GMPO_BD_EXMPFREE' | '???'
'6.19K'   | '1%'      | '1/16W' | '0402'    | 'EMPTY'  | 'G21796-161'(!) = 'YES;YES;YES;UNK;OK;VLD'           | 'G21796-161' | 'SMR0402A' | '(SMX0402,SMX0402A,SMX0402B)' | 'NA'     | '1%'    | '1/16W' | 'DISCRETE' | 'RES_D,0402,6.19KOHM,1.00%,1/16W'                       | '0.017 IN' | 'CHIP0402'     | ''          | '1141' | 'http://speed.intel.com:8081/speed/module/pdm/item/pdm_item_detail_direct.asp?item_cde=G21796-161&item_rev=01&url_param=unused' | 'UNQUAL'      | 'NO'  | '3'   | 'GMPO_BD_EXMPFREE' | '???'
'20.0'    | '1%'      | '1/16W' | '0402'    | 'EMPTY'  | 'G21796-173'(!) = 'YES;YES;YES;UNK;OK;VLD'           | 'G21796-173' | 'SMR0402A' | '(SMX0402,SMX0402A,SMX0402B)' | 'NA'     | '1%'    | '1/16W' | 'DISCRETE' | 'RES_D,0402,20.0OHM,1.00%,1/16W'                        | '0.017 IN' | 'CHIP0402'     | ''          | '1141' | 'http://speed.intel.com:8081/speed/module/pdm/item/pdm_item_detail_direct.asp?item_cde=G21796-173&item_rev=01&url_param=unused' | 'DESIGN'      | 'NO'  | '3'   | 'GMPO_BD_EXMPFREE' | '???'
'20.0'    | '1%'      | '1/16W' | '0402'    | 'CHIP'   | 'G21796-173'(!) = 'YES;YES;YES;UNK;OK;VLD'           | 'G21796-173' | 'SMR0402A' | '(SMX0402,SMX0402A,SMX0402B)' | '20.0'   | '1%'    | '1/16W' | 'DISCRETE' | 'RES_D,0402,20.0OHM,1.00%,1/16W'                        | '0.017 IN' | 'CHIP0402'     | ''          | '1141' | 'http://speed.intel.com:8081/speed/module/pdm/item/pdm_item_detail_direct.asp?item_cde=G21796-173&item_rev=01&url_param=unused' | 'DESIGN'      | 'NO'  | '3'   | 'GMPO_BD_EXMPFREE' | '???'
'7.5K'    | '1%'      | '1/16W' | '0402'    | 'CHIP'   | 'G21796-177'(!) = 'YES;YES;YES;UNK;OK;VLD'           | 'G21796-177' | 'SMR0402A' | '(SMX0402,SMX0402A,SMX0402B)' | '7.5K'   | '1%'    | '1/16W' | 'DISCRETE' | 'RES_D,0402,7.5KOHM,1.00%,1/16W'                        | '0.017 IN' | 'CHIP0402'     | ''          | '1141' | 'http://speed.intel.com:8081/speed/module/pdm/item/pdm_item_detail_direct.asp?item_cde=G21796-177&item_rev=01&url_param=unused' | 'UNQUAL'      | 'NO'  | '3'   | 'GMPO_BD_EXMPFREE' | '???'
'7.5K'    | '1%'      | '1/16W' | '0402'    | 'EMPTY'  | 'G21796-177'(!) = 'YES;YES;YES;UNK;OK;VLD'           | 'G21796-177' | 'SMR0402A' | '(SMX0402,SMX0402A,SMX0402B)' | 'NA'     | '1%'    | '1/16W' | 'DISCRETE' | 'RES_D,0402,7.5KOHM,1.00%,1/16W'                        | '0.017 IN' | 'CHIP0402'     | ''          | '1141' | 'http://speed.intel.com:8081/speed/module/pdm/item/pdm_item_detail_direct.asp?item_cde=G21796-177&item_rev=01&url_param=unused' | 'UNQUAL'      | 'NO'  | '3'   | 'GMPO_BD_EXMPFREE' | '???'
'2.67K'   | '1%'      | '1/16W' | '0402'    | 'EMPTY'  | 'G21796-180'(!) = 'YES;YES;YES;UNK;OK;VLD'           | 'G21796-180' | 'SMR0402A' | '(SMX0402,SMX0402A,SMX0402B)' | 'NA'     | '1%'    | '1/16W' | 'DISCRETE' | 'RES_D,0402,2.67KOHM,1.00%,1/16W'                       | '0.017 IN' | 'CHIP0402'     | ''          | '1141' | 'http://speed.intel.com:8081/speed/module/pdm/item/pdm_item_detail_direct.asp?item_cde=G21796-180&item_rev=01&url_param=unused' | 'DESIGN'      | 'NO'  | '3'   | 'GMPO_BD_EXMPFREE' | '???'
'2.67K'   | '1%'      | '1/16W' | '0402'    | 'CHIP'   | 'G21796-180'(!) = 'YES;YES;YES;UNK;OK;VLD'           | 'G21796-180' | 'SMR0402A' | '(SMX0402,SMX0402A,SMX0402B)' | '2.67K'  | '1%'    | '1/16W' | 'DISCRETE' | 'RES_D,0402,2.67KOHM,1.00%,1/16W'                       | '0.017 IN' | 'CHIP0402'     | ''          | '1141' | 'http://speed.intel.com:8081/speed/module/pdm/item/pdm_item_detail_direct.asp?item_cde=G21796-180&item_rev=01&url_param=unused' | 'DESIGN'      | 'NO'  | '3'   | 'GMPO_BD_EXMPFREE' | '???'
'27.4'    | '1%'      | '1/16W' | '0402'    | 'CHIP'   | 'G21796-182'(!) = 'YES;YES;YES;UNK;OK;VLD'           | 'G21796-182' | 'SMR0402A' | '(SMX0402,SMX0402A,SMX0402B)' | '27.4'   | '1%'    | '1/16W' | 'DISCRETE' | 'RES_D,0402,27.4OHM,1.00%,1/16W'                        | '0.017 IN' | 'CHIP0402'     | ''          | '1141' | 'http://speed.intel.com:8081/speed/module/pdm/item/pdm_item_detail_direct.asp?item_cde=G21796-182&item_rev=01&url_param=unused' | 'DESIGN'      | 'NO'  | '3'   | 'GMPO_BD_EXMPFREE' | '???'
'27.4'    | '1%'      | '1/16W' | '0402'    | 'EMPTY'  | 'G21796-182'(!) = 'YES;YES;YES;UNK;OK;VLD'           | 'G21796-182' | 'SMR0402A' | '(SMX0402,SMX0402A,SMX0402B)' | 'NA'     | '1%'    | '1/16W' | 'DISCRETE' | 'RES_D,0402,27.4OHM,1.00%,1/16W'                        | '0.017 IN' | 'CHIP0402'     | ''          | '1141' | 'http://speed.intel.com:8081/speed/module/pdm/item/pdm_item_detail_direct.asp?item_cde=G21796-182&item_rev=01&url_param=unused' | 'DESIGN'      | 'NO'  | '3'   | 'GMPO_BD_EXMPFREE' | '???'
'68.1K'   | '1%'      | '1/16W' | '0402'    | 'EMPTY'  | 'G21796-187'(!) = 'YES;YES;YES;UNK;OK;VLD'           | 'G21796-187' | 'SMR0402A' | '(SMX0402,SMX0402A,SMX0402B)' | 'NA'     | '1%'    | '1/16W' | 'DISCRETE' | 'RES_D,0402,68.1KOHM,1.00%,1/16W'                       | '0.017 IN' | 'CHIP0402'     | ''          | '1141' | 'http://speed.intel.com:8081/speed/module/pdm/item/pdm_item_detail_direct.asp?item_cde=G21796-187&item_rev=01&url_param=unused' | 'DESIGN'      | 'NO'  | '3'   | 'GMPO_BD_EXMPFREE' | '???'
'68.1K'   | '1%'      | '1/16W' | '0402'    | 'CHIP'   | 'G21796-187'(!) = 'YES;YES;YES;UNK;OK;VLD'           | 'G21796-187' | 'SMR0402A' | '(SMX0402,SMX0402A,SMX0402B)' | '68.1K'  | '1%'    | '1/16W' | 'DISCRETE' | 'RES_D,0402,68.1KOHM,1.00%,1/16W'                       | '0.017 IN' | 'CHIP0402'     | ''          | '1141' | 'http://speed.intel.com:8081/speed/module/pdm/item/pdm_item_detail_direct.asp?item_cde=G21796-187&item_rev=01&url_param=unused' | 'DESIGN'      | 'NO'  | '3'   | 'GMPO_BD_EXMPFREE' | '???'
'249K'    | '1.0%'    | '1/16W' | '0402'    | 'CHIP'   | 'G21796-189'(!) = 'YES;YES;YES;UNK;OK;VLD'           | 'G21796-189' | 'SMR0402A' | '(SMX0402,SMX0402A,SMX0402B)' | '249K'   | '1.0%'  | '1/16W' | 'DISCRETE' | 'RES_D,0402,249.00KOHM,1.00%,1/16W,'                    | '0.016 IN' | 'CHIP0402'     | ''          | '1141' | 'http://speed.intel.com:8081/speed/module/pdm/item/pdm_item_detail_direct.asp?item_cde=G21796-189&item_rev=01&url_param=unused' | 'DESIGN'      | 'NO'  | '3'   | 'GMPO_BD_EXMPFREE' | '???'
'249K'    | '1.0%'    | '1/16W' | '0402'    | 'EMPTY'  | 'G21796-189'(!) = 'YES;YES;YES;UNK;OK;VLD'           | 'G21796-189' | 'SMR0402A' | '(SMX0402,SMX0402A,SMX0402B)' | 'NA'     | '1.0%'  | '1/16W' | 'DISCRETE' | 'RES_D,0402,249.00KOHM,1.00%,1/16W,'                    | '0.016 IN' | 'CHIP0402'     | ''          | '1141' | 'http://speed.intel.com:8081/speed/module/pdm/item/pdm_item_detail_direct.asp?item_cde=G21796-189&item_rev=01&url_param=unused' | 'DESIGN'      | 'NO'  | '3'   | 'GMPO_BD_EXMPFREE' | '???'
'110'     | '1%'      | '1/16W' | '0402'    | 'CHIP'   | 'G21796-203'(!) = ''                                 | 'G21796-203' | 'SMR0402A' | '(SMX0402,SMX0402A,SMX0402B)' | '110'    | '1%'    | '1/16W' | 'DISCRETE' | 'RES_D,0402,110.00OHM,1.00%,1/16W,'                     | '0.016 IN' | 'CHIP0402'     | ''          | '1141' | 'http://speed.intel.com:8081/speed/module/pdm/item/pdm_item_detail_direct.asp?item_cde=G21796-203&item_rev=01&url_param=unused' | ''            | ''    | ''    | ''                 | ''   
'110'     | '1%'      | '1/16W' | '0402'    | 'EMPTY'  | 'G21796-203'(!) = ''                                 | 'G21796-203' | 'SMR0402A' | '(SMX0402,SMX0402A,SMX0402B)' | 'NA'     | '1%'    | '1/16W' | 'DISCRETE' | 'RES_D,0402,110.00OHM,1.00%,1/16W,'                     | '0.016 IN' | 'CHIP0402'     | ''          | '1141' | 'http://speed.intel.com:8081/speed/module/pdm/item/pdm_item_detail_direct.asp?item_cde=G21796-203&item_rev=01&url_param=unused' | ''            | ''    | ''    | ''                 | ''   
'51.1'    | '1.0%'    | '1/16W' | '0402'    | 'EMPTY'  | 'G21796-208'(!) = 'YES;YES;YES;UNK;OK;VLD'           | 'G21796-208' | 'SMR0402A' | '(SMX0402,SMX0402A,SMX0402B)' | 'NA'     | '1.0%'  | '1/16W' | 'DISCRETE' | 'RES_D,0402,51.10OHM,1.00%,1/16W,'                      | '0.016 IN' | 'CHIP0402'     | ''          | '1141' | 'http://speed.intel.com:8081/speed/module/pdm/item/pdm_item_detail_direct.asp?item_cde=G21796-208&item_rev=01&url_param=unused' | 'DESIGN'      | 'NO'  | '3'   | 'GMPO_BD_EXMPFREE' | '???'
'51.1'    | '1.0%'    | '1/16W' | '0402'    | 'CHIP'   | 'G21796-208'(!) = 'YES;YES;YES;UNK;OK;VLD'           | 'G21796-208' | 'SMR0402A' | '(SMX0402,SMX0402A,SMX0402B)' | '51.1'   | '1.0%'  | '1/16W' | 'DISCRETE' | 'RES_D,0402,51.10OHM,1.00%,1/16W,'                      | '0.016 IN' | 'CHIP0402'     | ''          | '1141' | 'http://speed.intel.com:8081/speed/module/pdm/item/pdm_item_detail_direct.asp?item_cde=G21796-208&item_rev=01&url_param=unused' | 'DESIGN'      | 'NO'  | '3'   | 'GMPO_BD_EXMPFREE' | '???'
'11K'     | '1%'      | '1/16W' | '0402'    | 'EMPTY'  | 'G21796-220'(!) = ''                                 | 'G21796-220' | 'SMR0402A' | '(SMX0402,SMX0402A,SMX0402B)' | 'NA'     | '1%'    | '1/16W' | 'DISCRETE' | 'RES_D,0402,11.00kOHM,1.00%,1/16W,'                     | '0.016 IN' | 'CHIP0402'     | ''          | '1141' | 'http://speed.intel.com:8081/speed/module/pdm/item/pdm_item_detail_direct.asp?item_cde=G21796-220&item_rev=01&url_param=unused' | ''            | ''    | ''    | ''                 | ''   
'11K'     | '1%'      | '1/16W' | '0402'    | 'CHIP'   | 'G21796-220'(!) = ''                                 | 'G21796-220' | 'SMR0402A' | '(SMX0402,SMX0402A,SMX0402B)' | '11K'    | '1%'    | '1/16W' | 'DISCRETE' | 'RES_D,0402,11.00kOHM,1.00%,1/16W,'                     | '0.016 IN' | 'CHIP0402'     | ''          | '1141' | 'http://speed.intel.com:8081/speed/module/pdm/item/pdm_item_detail_direct.asp?item_cde=G21796-220&item_rev=01&url_param=unused' | ''            | ''    | ''    | ''                 | ''   
'13K'     | '1.0%'    | '1/16W' | '0402'    | 'EMPTY'  | 'G21796-221'(!) = 'YES;YES;YES;UNK;OK;VLD'           | 'G21796-221' | 'SMR0402A' | '(SMX0402,SMX0402A,SMX0402B)' | 'NA'     | '1.0%'  | '1/16W' | 'DISCRETE' | 'RES_D,0402,13.00KOHM,1.00%,1/16W,'                     | '0.016 IN' | 'CHIP0402'     | ''          | '1141' | 'http://speed.intel.com:8081/speed/module/pdm/item/pdm_item_detail_direct.asp?item_cde=G21796-221&item_rev=01&url_param=unused' | 'DESIGN'      | 'NO'  | '3'   | 'GMPO_BD_EXMPFREE' | '???'
'13K'     | '1.0%'    | '1/16W' | '0402'    | 'CHIP'   | 'G21796-221'(!) = 'YES;YES;YES;UNK;OK;VLD'           | 'G21796-221' | 'SMR0402A' | '(SMX0402,SMX0402A,SMX0402B)' | '13K'    | '1.0%'  | '1/16W' | 'DISCRETE' | 'RES_D,0402,13.00KOHM,1.00%,1/16W,'                     | '0.016 IN' | 'CHIP0402'     | ''          | '1141' | 'http://speed.intel.com:8081/speed/module/pdm/item/pdm_item_detail_direct.asp?item_cde=G21796-221&item_rev=01&url_param=unused' | 'DESIGN'      | 'NO'  | '3'   | 'GMPO_BD_EXMPFREE' | '???'
'75K'     | '1%'      | '1/16W' | '0402'    | 'EMPTY'  | 'G21796-224'(!) = ''                                 | 'G21796-224' | 'SMR0402A' | '(SMX0402,SMX0402A,SMX0402B)' | 'NA'     | '1%'    | '1/16W' | 'DISCRETE' | 'RES_D,0402,75.00kOHM,1.00%,1/16W,'                     | '0.016 IN' | 'CHIP0402'     | ''          | '1141' | 'http://speed.intel.com:8081/speed/module/pdm/item/pdm_item_detail_direct.asp?item_cde=G21796-224&item_rev=01&url_param=unused' | ''            | ''    | ''    | ''                 | ''   
'75K'     | '1%'      | '1/16W' | '0402'    | 'CHIP'   | 'G21796-224'(!) = ''                                 | 'G21796-224' | 'SMR0402A' | '(SMX0402,SMX0402A,SMX0402B)' | '75K'    | '1%'    | '1/16W' | 'DISCRETE' | 'RES_D,0402,75.00kOHM,1.00%,1/16W,'                     | '0.016 IN' | 'CHIP0402'     | ''          | '1141' | 'http://speed.intel.com:8081/speed/module/pdm/item/pdm_item_detail_direct.asp?item_cde=G21796-224&item_rev=01&url_param=unused' | ''            | ''    | ''    | ''                 | ''   
'665'     | '1.0%'    | '1/16W' | '0402'    | 'EMPTY'  | 'G21796-235'(!) = 'YES;YES;YES;UNK;OK;VLD'           | 'G21796-235' | 'SMR0402A' | '(SMX0402,SMX0402A,SMX0402B)' | 'NA'     | '1.0%'  | '1/16W' | 'DISCRETE' | 'RES_D,0402,665.00OHM,1.00%,1/16W,'                     | '0.016 IN' | 'CHIP0402'     | ''          | '1141' | 'http://speed.intel.com:8081/speed/module/pdm/item/pdm_item_detail_direct.asp?item_cde=G21796-235&item_rev=01&url_param=unused' | 'DESIGN'      | 'NO'  | '3'   | 'GMPO_BD_EXMPFREE' | '???'
'665'     | '1.0%'    | '1/16W' | '0402'    | 'CHIP'   | 'G21796-235'(!) = 'YES;YES;YES;UNK;OK;VLD'           | 'G21796-235' | 'SMR0402A' | '(SMX0402,SMX0402A,SMX0402B)' | '665'    | '1.0%'  | '1/16W' | 'DISCRETE' | 'RES_D,0402,665.00OHM,1.00%,1/16W,'                     | '0.016 IN' | 'CHIP0402'     | ''          | '1141' | 'http://speed.intel.com:8081/speed/module/pdm/item/pdm_item_detail_direct.asp?item_cde=G21796-235&item_rev=01&url_param=unused' | 'DESIGN'      | 'NO'  | '3'   | 'GMPO_BD_EXMPFREE' | '???'
'7.87K'   | '1.0%'    | '1/16W' | '0402'    | 'EMPTY'  | 'G21796-242'(!) = 'YES;YES;YES;UNK;OK;VLD'           | 'G21796-242' | 'SMR0402A' | '(SMX0402,SMX0402A,SMX0402B)' | 'NA'     | '1.0%'  | '1/16W' | 'DISCRETE' | 'RES_D,0402,7.87KOHM,1.00%,1/16W,'                      | '0.016 IN' | 'CHIP0402'     | ''          | '1141' | 'http://speed.intel.com:8081/speed/module/pdm/item/pdm_item_detail_direct.asp?item_cde=G21796-242&item_rev=01&url_param=unused' | 'DESIGN'      | 'NO'  | '3'   | 'GMPO_BD_EXMPFREE' | '???'
'7.87K'   | '1.0%'    | '1/16W' | '0402'    | 'CHIP'   | 'G21796-242'(!) = 'YES;YES;YES;UNK;OK;VLD'           | 'G21796-242' | 'SMR0402A' | '(SMX0402,SMX0402A,SMX0402B)' | '7.87K'  | '1.0%'  | '1/16W' | 'DISCRETE' | 'RES_D,0402,7.87KOHM,1.00%,1/16W,'                      | '0.016 IN' | 'CHIP0402'     | ''          | '1141' | 'http://speed.intel.com:8081/speed/module/pdm/item/pdm_item_detail_direct.asp?item_cde=G21796-242&item_rev=01&url_param=unused' | 'DESIGN'      | 'NO'  | '3'   | 'GMPO_BD_EXMPFREE' | '???'
'22.1'    | '1.0%'    | '1/16W' | '0402'    | 'EMPTY'  | 'G21796-250'(!) = 'YES;YES;YES;UNK;OK;VLD'           | 'G21796-250' | 'SMR0402A' | '(SMX0402,SMX0402A,SMX0402B)' | 'NA'     | '1.0%'  | '1/16W' | 'DISCRETE' | 'RES_D,0402,22.10OHM,1.00%,1/16W,'                      | '0.016 IN' | 'CHIP0402'     | ''          | '1141' | 'http://speed.intel.com:8081/speed/module/pdm/item/pdm_item_detail_direct.asp?item_cde=G21796-250&item_rev=01&url_param=unused' | 'DESIGN'      | 'NO'  | '3'   | 'GMPO_BD_EXMPFREE' | '???'
'22.1'    | '1.0%'    | '1/16W' | '0402'    | 'CHIP'   | 'G21796-250'(!) = 'YES;YES;YES;UNK;OK;VLD'           | 'G21796-250' | 'SMR0402A' | '(SMX0402,SMX0402A,SMX0402B)' | '22.1'   | '1.0%'  | '1/16W' | 'DISCRETE' | 'RES_D,0402,22.10OHM,1.00%,1/16W,'                      | '0.016 IN' | 'CHIP0402'     | ''          | '1141' | 'http://speed.intel.com:8081/speed/module/pdm/item/pdm_item_detail_direct.asp?item_cde=G21796-250&item_rev=01&url_param=unused' | 'DESIGN'      | 'NO'  | '3'   | 'GMPO_BD_EXMPFREE' | '???'
'24.9K'   | '1%'      | '1/16W' | '0402'    | 'EMPTY'  | 'G21796-254'(!) = ''                                 | 'G21796-254' | 'SMR0402A' | '(SMX0402,SMX0402A,SMX0402B)' | 'NA'     | '1%'    | '1/16W' | 'DISCRETE' | 'RES_D,0402,24.90kOHM,1.00%,1/16W,'                     | '0.016 IN' | 'CHIP0402'     | ''          | '1141' | 'http://speed.intel.com:8081/speed/module/pdm/item/pdm_item_detail_direct.asp?item_cde=G21796-254&item_rev=01&url_param=unused' | ''            | ''    | ''    | ''                 | ''   
'24.9K'   | '1%'      | '1/16W' | '0402'    | 'CHIP'   | 'G21796-254'(!) = ''                                 | 'G21796-254' | 'SMR0402A' | '(SMX0402,SMX0402A,SMX0402B)' | '24.9K'  | '1%'    | '1/16W' | 'DISCRETE' | 'RES_D,0402,24.90kOHM,1.00%,1/16W,'                     | '0.016 IN' | 'CHIP0402'     | ''          | '1141' | 'http://speed.intel.com:8081/speed/module/pdm/item/pdm_item_detail_direct.asp?item_cde=G21796-254&item_rev=01&url_param=unused' | ''            | ''    | ''    | ''                 | ''   
'42.2'    | '1.0%'    | '1/16W' | '0402'    | 'EMPTY'  | 'G21796-259'(!) = 'YES;YES;YES;UNK;OK;VLD'           | 'G21796-259' | 'SMR0402A' | '(SMX0402,SMX0402A,SMX0402B)' | 'NA'     | '1.0%'  | '1/16W' | 'DISCRETE' | 'RES_D,0402,42.20OHM,1.00%,1/16W,'                      | '0.016 IN' | 'CHIP0402'     | ''          | '1141' | 'http://speed.intel.com:8081/speed/module/pdm/item/pdm_item_detail_direct.asp?item_cde=G21796-259&item_rev=01&url_param=unused' | 'DESIGN'      | 'NO'  | '3'   | 'GMPO_BD_EXMPFREE' | '???'
'42.2'    | '1.0%'    | '1/16W' | '0402'    | 'CHIP'   | 'G21796-259'(!) = 'YES;YES;YES;UNK;OK;VLD'           | 'G21796-259' | 'SMR0402A' | '(SMX0402,SMX0402A,SMX0402B)' | '42.2'   | '1.0%'  | '1/16W' | 'DISCRETE' | 'RES_D,0402,42.20OHM,1.00%,1/16W,'                      | '0.016 IN' | 'CHIP0402'     | ''          | '1141' | 'http://speed.intel.com:8081/speed/module/pdm/item/pdm_item_detail_direct.asp?item_cde=G21796-259&item_rev=01&url_param=unused' | 'DESIGN'      | 'NO'  | '3'   | 'GMPO_BD_EXMPFREE' | '???'
'12K'     | '1%'      | '1/16W' | '0402'    | 'CHIP'   | 'G21796-264'(!) = ''                                 | 'G21796-264' | 'SMR0402A' | '(SMX0402,SMX0402A,SMX0402B)' | '12K'    | '1%'    | '1/16W' | 'DISCRETE' | 'RES_D,0402,12.00kOHM,1.00%,1/16W,'                     | '0.016 IN' | 'CHIP0402'     | ''          | '1141' | 'http://speed.intel.com:8081/speed/module/pdm/item/pdm_item_detail_direct.asp?item_cde=G21796-264&item_rev=01&url_param=unused' | ''            | ''    | ''    | ''                 | ''   
'12K'     | '1%'      | '1/16W' | '0402'    | 'EMPTY'  | 'G21796-264'(!) = ''                                 | 'G21796-264' | 'SMR0402A' | '(SMX0402,SMX0402A,SMX0402B)' | 'NA'     | '1%'    | '1/16W' | 'DISCRETE' | 'RES_D,0402,12.00kOHM,1.00%,1/16W,'                     | '0.016 IN' | 'CHIP0402'     | ''          | '1141' | 'http://speed.intel.com:8081/speed/module/pdm/item/pdm_item_detail_direct.asp?item_cde=G21796-264&item_rev=01&url_param=unused' | ''            | ''    | ''    | ''                 | ''   
'75'      | '1.0%'    | '1/16W' | '0402'    | 'EMPTY'  | 'G21796-267'(!) = 'YES;YES;YES;UNK;OK;VLD'           | 'G21796-267' | 'SMR0402A' | '(SMX0402,SMX0402A,SMX0402B)' | 'NA'     | '1.0%'  | '1/16W' | 'DISCRETE' | 'RES_D,0402,75.00OHM,1.00%,1/16W,'                      | '0.016 IN' | 'CHIP0402'     | ''          | '1141' | 'http://speed.intel.com:8081/speed/module/pdm/item/pdm_item_detail_direct.asp?item_cde=G21796-267&item_rev=01&url_param=unused' | 'DESIGN'      | 'NO'  | '3'   | 'GMPO_BD_EXMPFREE' | '???'
'75'      | '1.0%'    | '1/16W' | '0402'    | 'CHIP'   | 'G21796-267'(!) = 'YES;YES;YES;UNK;OK;VLD'           | 'G21796-267' | 'SMR0402A' | '(SMX0402,SMX0402A,SMX0402B)' | '75'     | '1.0%'  | '1/16W' | 'DISCRETE' | 'RES_D,0402,75.00OHM,1.00%,1/16W,'                      | '0.016 IN' | 'CHIP0402'     | ''          | '1141' | 'http://speed.intel.com:8081/speed/module/pdm/item/pdm_item_detail_direct.asp?item_cde=G21796-267&item_rev=01&url_param=unused' | 'DESIGN'      | 'NO'  | '3'   | 'GMPO_BD_EXMPFREE' | '???'
'221'     | '1.0%'    | '1/16W' | '0402'    | 'CHIP'   | 'G21796-271'(!) = 'YES;YES;YES;UNK;OK;VLD'           | 'G21796-271' | 'SMR0402A' | '(SMX0402,SMX0402A,SMX0402B)' | '221'    | '1.0%'  | '1/16W' | 'DISCRETE' | 'RES_D,0402,221.00OHM,1.00%,1/16W,'                     | '0.016 IN' | 'CHIP0402'     | ''          | '1141' | 'http://speed.intel.com:8081/speed/module/pdm/item/pdm_item_detail_direct.asp?item_cde=G21796-271&item_rev=01&url_param=unused' | 'DESIGN'      | 'NO'  | '3'   | 'GMPO_BD_EXMPFREE' | '???'
'221'     | '1.0%'    | '1/16W' | '0402'    | 'EMPTY'  | 'G21796-271'(!) = 'YES;YES;YES;UNK;OK;VLD'           | 'G21796-271' | 'SMR0402A' | '(SMX0402,SMX0402A,SMX0402B)' | 'NA'     | '1.0%'  | '1/16W' | 'DISCRETE' | 'RES_D,0402,221.00OHM,1.00%,1/16W,'                     | '0.016 IN' | 'CHIP0402'     | ''          | '1141' | 'http://speed.intel.com:8081/speed/module/pdm/item/pdm_item_detail_direct.asp?item_cde=G21796-271&item_rev=01&url_param=unused' | 'DESIGN'      | 'NO'  | '3'   | 'GMPO_BD_EXMPFREE' | '???'
'2'       | '1.0%'    | '1/16W' | '0402'    | 'EMPTY'  | 'G21796-274'(!) = 'YES;YES;YES;UNK;OK;VLD'           | 'G21796-274' | 'SMR0402A' | '(SMX0402,SMX0402A,SMX0402B)' | 'NA'     | '1.0%'  | '1/16W' | 'DISCRETE' | 'RES_D,0402,2.00OHM,1.00%,1/16W,'                       | '0.016 IN' | 'CHIP0402'     | ''          | '1141' | 'http://speed.intel.com:8081/speed/module/pdm/item/pdm_item_detail_direct.asp?item_cde=G21796-274&item_rev=01&url_param=unused' | 'DESIGN'      | 'NO'  | '2'   | 'GMPO_BD_EXMPFREE' | '???'
'2'       | '1.0%'    | '1/16W' | '0402'    | 'CHIP'   | 'G21796-274'(!) = 'YES;YES;YES;UNK;OK;VLD'           | 'G21796-274' | 'SMR0402A' | '(SMX0402,SMX0402A,SMX0402B)' | '2'      | '1.0%'  | '1/16W' | 'DISCRETE' | 'RES_D,0402,2.00OHM,1.00%,1/16W,'                       | '0.016 IN' | 'CHIP0402'     | ''          | '1141' | 'http://speed.intel.com:8081/speed/module/pdm/item/pdm_item_detail_direct.asp?item_cde=G21796-274&item_rev=01&url_param=unused' | 'DESIGN'      | 'NO'  | '2'   | 'GMPO_BD_EXMPFREE' | '???'
'169'     | '1.0%'    | '1/16W' | '0402'    | 'CHIP'   | 'G21796-276'(!) = 'YES;YES;YES;UNK;OK;VLD'           | 'G21796-276' | 'SMR0402A' | '(SMX0402,SMX0402A,SMX0402B)' | '169'    | '1.0%'  | '1/16W' | 'DISCRETE' | 'RES_D,0402,169.00OHM,1.00%,1/16W,'                     | '0.016 IN' | 'CHIP0402'     | ''          | '1141' | 'http://speed.intel.com:8081/speed/module/pdm/item/pdm_item_detail_direct.asp?item_cde=G21796-276&item_rev=01&url_param=unused' | 'DESIGN'      | 'NO'  | '3'   | 'GMPO_BD_EXMPFREE' | '???'
'169'     | '1.0%'    | '1/16W' | '0402'    | 'EMPTY'  | 'G21796-276'(!) = 'YES;YES;YES;UNK;OK;VLD'           | 'G21796-276' | 'SMR0402A' | '(SMX0402,SMX0402A,SMX0402B)' | 'NA'     | '1.0%'  | '1/16W' | 'DISCRETE' | 'RES_D,0402,169.00OHM,1.00%,1/16W,'                     | '0.016 IN' | 'CHIP0402'     | ''          | '1141' | 'http://speed.intel.com:8081/speed/module/pdm/item/pdm_item_detail_direct.asp?item_cde=G21796-276&item_rev=01&url_param=unused' | 'DESIGN'      | 'NO'  | '3'   | 'GMPO_BD_EXMPFREE' | '???'
'3.48K'   | '1.0%'    | '1/16W' | '0402'    | 'CHIP'   | 'G21796-279'(!) = 'YES;YES;YES;UNK;OK;VLD'           | 'G21796-279' | 'SMR0402A' | '(SMX0402,SMX0402A,SMX0402B)' | '3.48K'  | '1.0%'  | '1/16W' | 'DISCRETE' | 'RES_D,0402,3.48KOHM,1.00%,1/16W,'                      | '0.016 IN' | 'CHIP0402'     | ''          | '1141' | 'http://speed.intel.com:8081/speed/module/pdm/item/pdm_item_detail_direct.asp?item_cde=G21796-279&item_rev=01&url_param=unused' | 'DESIGN'      | 'NO'  | '3'   | 'GMPO_BD_EXMPFREE' | '???'
'3.48K'   | '1.0%'    | '1/16W' | '0402'    | 'EMPTY'  | 'G21796-279'(!) = 'YES;YES;YES;UNK;OK;VLD'           | 'G21796-279' | 'SMR0402A' | '(SMX0402,SMX0402A,SMX0402B)' | 'NA'     | '1.0%'  | '1/16W' | 'DISCRETE' | 'RES_D,0402,3.48KOHM,1.00%,1/16W,'                      | '0.016 IN' | 'CHIP0402'     | ''          | '1141' | 'http://speed.intel.com:8081/speed/module/pdm/item/pdm_item_detail_direct.asp?item_cde=G21796-279&item_rev=01&url_param=unused' | 'DESIGN'      | 'NO'  | '3'   | 'GMPO_BD_EXMPFREE' | '???'
'240'     | '1.0%'    | '1/16W' | '0402'    | 'CHIP'   | 'G21796-294'(!) = 'YES;YES;YES;UNK;OK;VLD'           | 'G21796-294' | 'SMR0402A' | '(SMX0402,SMX0402A,SMX0402B)' | '240'    | '1.0%'  | '1/16W' | 'DISCRETE' | 'RES_D,0402,240.00OHM,1.00%,1/16W,'                     | '0.016 IN' | 'CHIP0402'     | ''          | '1141' | 'http://speed.intel.com:8081/speed/module/pdm/item/pdm_item_detail_direct.asp?item_cde=G21796-294&item_rev=01&url_param=unused' | 'DESIGN'      | 'NO'  | '3'   | 'GMPO_BD_EXMPFREE' | '???'
'240'     | '1.0%'    | '1/16W' | '0402'    | 'EMPTY'  | 'G21796-294'(!) = 'YES;YES;YES;UNK;OK;VLD'           | 'G21796-294' | 'SMR0402A' | '(SMX0402,SMX0402A,SMX0402B)' | 'NA'     | '1.0%'  | '1/16W' | 'DISCRETE' | 'RES_D,0402,240.00OHM,1.00%,1/16W,'                     | '0.016 IN' | 'CHIP0402'     | ''          | '1141' | 'http://speed.intel.com:8081/speed/module/pdm/item/pdm_item_detail_direct.asp?item_cde=G21796-294&item_rev=01&url_param=unused' | 'DESIGN'      | 'NO'  | '3'   | 'GMPO_BD_EXMPFREE' | '???'
'5.36K'   | '1.0%'    | '1/16W' | '0402'    | 'CHIP'   | 'G21796-297'(!) = 'YES;YES;YES;UNK;OK;VLD'           | 'G21796-297' | 'SMR0402A' | '(SMX0402,SMX0402A,SMX0402B)' | '5.36K'  | '1.0%'  | '1/16W' | 'DISCRETE' | 'RES_D,0402,5.36KOHM,1.00%,1/16W,'                      | '0.016 IN' | 'CHIP0402'     | ''          | '1141' | 'http://speed.intel.com:8081/speed/module/pdm/item/pdm_item_detail_direct.asp?item_cde=G21796-297&item_rev=01&url_param=unused' | 'DESIGN'      | 'NO'  | '3'   | 'GMPO_BD_EXMPFREE' | '???'
'5.36K'   | '1.0%'    | '1/16W' | '0402'    | 'EMPTY'  | 'G21796-297'(!) = 'YES;YES;YES;UNK;OK;VLD'           | 'G21796-297' | 'SMR0402A' | '(SMX0402,SMX0402A,SMX0402B)' | 'NA'     | '1.0%'  | '1/16W' | 'DISCRETE' | 'RES_D,0402,5.36KOHM,1.00%,1/16W,'                      | '0.016 IN' | 'CHIP0402'     | ''          | '1141' | 'http://speed.intel.com:8081/speed/module/pdm/item/pdm_item_detail_direct.asp?item_cde=G21796-297&item_rev=01&url_param=unused' | 'DESIGN'      | 'NO'  | '3'   | 'GMPO_BD_EXMPFREE' | '???'
'64.9'    | '1.0%'    | '1/16W' | '0402'    | 'EMPTY'  | 'G21796-298'(!) = 'YES;YES;YES;UNK;OK;VLD'           | 'G21796-298' | 'SMR0402A' | '(SMX0402,SMX0402A,SMX0402B)' | 'NA'     | '1.0%'  | '1/16W' | 'DISCRETE' | 'RES_D,0402,64.90OHM,1.00%,1/16W,'                      | '0.016 IN' | 'CHIP0402'     | ''          | '1141' | 'http://speed.intel.com:8081/speed/module/pdm/item/pdm_item_detail_direct.asp?item_cde=G21796-298&item_rev=01&url_param=unused' | 'DESIGN'      | 'NO'  | '3'   | 'GMPO_BD_EXMPFREE' | '???'
'64.9'    | '1.0%'    | '1/16W' | '0402'    | 'CHIP'   | 'G21796-298'(!) = 'YES;YES;YES;UNK;OK;VLD'           | 'G21796-298' | 'SMR0402A' | '(SMX0402,SMX0402A,SMX0402B)' | '64.9'   | '1.0%'  | '1/16W' | 'DISCRETE' | 'RES_D,0402,64.90OHM,1.00%,1/16W,'                      | '0.016 IN' | 'CHIP0402'     | ''          | '1141' | 'http://speed.intel.com:8081/speed/module/pdm/item/pdm_item_detail_direct.asp?item_cde=G21796-298&item_rev=01&url_param=unused' | 'DESIGN'      | 'NO'  | '3'   | 'GMPO_BD_EXMPFREE' | '???'
'2.26K'   | '1.0%'    | '1/16W' | '0402'    | 'CHIP'   | 'G21796-311'(!) = 'YES;YES;YES;UNK;OK;VLD'           | 'G21796-311' | 'SMR0402A' | '(SMX0402,SMX0402A,SMX0402B)' | '2.26K'  | '1.0%'  | '1/16W' | 'DISCRETE' | 'RES_D,0402,2.26KOHM,1.00%,1/16W,'                      | '0.016 IN' | 'CHIP0402'     | ''          | '1141' | 'http://speed.intel.com:8081/speed/module/pdm/item/pdm_item_detail_direct.asp?item_cde=G21796-311&item_rev=01&url_param=unused' | 'DESIGN'      | 'NO'  | '3'   | 'GMPO_BD_EXMPFREE' | '???'
'2.26K'   | '1.0%'    | '1/16W' | '0402'    | 'EMPTY'  | 'G21796-311'(!) = 'YES;YES;YES;UNK;OK;VLD'           | 'G21796-311' | 'SMR0402A' | '(SMX0402,SMX0402A,SMX0402B)' | 'NA'     | '1.0%'  | '1/16W' | 'DISCRETE' | 'RES_D,0402,2.26KOHM,1.00%,1/16W,'                      | '0.016 IN' | 'CHIP0402'     | ''          | '1141' | 'http://speed.intel.com:8081/speed/module/pdm/item/pdm_item_detail_direct.asp?item_cde=G21796-311&item_rev=01&url_param=unused' | 'DESIGN'      | 'NO'  | '3'   | 'GMPO_BD_EXMPFREE' | '???'
'16K'     | '1.0%'    | '1/16W' | '0402'    | 'EMPTY'  | 'G21796-317'(!) = 'YES;YES;YES;UNK;OK;VLD'           | 'G21796-317' | 'SMR0402A' | '(SMX0402,SMX0402A,SMX0402B)' | 'NA'     | '1.0%'  | '1/16W' | 'DISCRETE' | 'RES_D,0402,16.00KOHM,1.00%,1/16W,'                     | '0.016 IN' | 'CHIP0402'     | ''          | '1141' | 'http://speed.intel.com:8081/speed/module/pdm/item/pdm_item_detail_direct.asp?item_cde=G21796-317&item_rev=01&url_param=unused' | 'DESIGN'      | 'NO'  | '3'   | 'GMPO_BD_EXMPFREE' | '???'
'16K'     | '1.0%'    | '1/16W' | '0402'    | 'CHIP'   | 'G21796-317'(!) = 'YES;YES;YES;UNK;OK;VLD'           | 'G21796-317' | 'SMR0402A' | '(SMX0402,SMX0402A,SMX0402B)' | '16K'    | '1.0%'  | '1/16W' | 'DISCRETE' | 'RES_D,0402,16.00KOHM,1.00%,1/16W,'                     | '0.016 IN' | 'CHIP0402'     | ''          | '1141' | 'http://speed.intel.com:8081/speed/module/pdm/item/pdm_item_detail_direct.asp?item_cde=G21796-317&item_rev=01&url_param=unused' | 'DESIGN'      | 'NO'  | '3'   | 'GMPO_BD_EXMPFREE' | '???'
'63.4K'   | '1.0%'    | '1/16W' | '0402'    | 'CHIP'   | 'G21796-327'(!) = 'YES;YES;YES;UNK;OK;VLD'           | 'G21796-327' | 'SMR0402A' | '(SMX0402,SMX0402A,SMX0402B)' | '63.4K'  | '1.0%'  | '1/16W' | 'DISCRETE' | 'RES_D,0402,63.40KOHM,1.00%,1/16W,'                     | '0.016 IN' | 'CHIP0402'     | ''          | '1141' | 'http://speed.intel.com:8081/speed/module/pdm/item/pdm_item_detail_direct.asp?item_cde=G21796-327&item_rev=01&url_param=unused' | 'DESIGN'      | 'NO'  | '3'   | 'GMPO_BD_EXMPFREE' | '???'
'63.4K'   | '1.0%'    | '1/16W' | '0402'    | 'EMPTY'  | 'G21796-327'(!) = 'YES;YES;YES;UNK;OK;VLD'           | 'G21796-327' | 'SMR0402A' | '(SMX0402,SMX0402A,SMX0402B)' | 'NA'     | '1.0%'  | '1/16W' | 'DISCRETE' | 'RES_D,0402,63.40KOHM,1.00%,1/16W,'                     | '0.016 IN' | 'CHIP0402'     | ''          | '1141' | 'http://speed.intel.com:8081/speed/module/pdm/item/pdm_item_detail_direct.asp?item_cde=G21796-327&item_rev=01&url_param=unused' | 'DESIGN'      | 'NO'  | '3'   | 'GMPO_BD_EXMPFREE' | '???'
'274K'    | '1.0%'    | '1/16W' | '0402'    | 'CHIP'   | 'G21796-331'(!) = 'YES;YES;YES;UNK;OK;VLD'           | 'G21796-331' | 'SMR0402A' | '(SMX0402,SMX0402A,SMX0402B)' | '274K'   | '1.0%'  | '1/16W' | 'DISCRETE' | 'RES_D,0402,274.00KOHM,1.00%,1/16W,'                    | '0.016 IN' | 'CHIP0402'     | ''          | '1141' | 'http://speed.intel.com:8081/speed/module/pdm/item/pdm_item_detail_direct.asp?item_cde=G21796-331&item_rev=01&url_param=unused' | 'DESIGN'      | 'NO'  | '3'   | 'GMPO_BD_EXMPFREE' | '???'
'274K'    | '1.0%'    | '1/16W' | '0402'    | 'EMPTY'  | 'G21796-331'(!) = 'YES;YES;YES;UNK;OK;VLD'           | 'G21796-331' | 'SMR0402A' | '(SMX0402,SMX0402A,SMX0402B)' | 'NA'     | '1.0%'  | '1/16W' | 'DISCRETE' | 'RES_D,0402,274.00KOHM,1.00%,1/16W,'                    | '0.016 IN' | 'CHIP0402'     | ''          | '1141' | 'http://speed.intel.com:8081/speed/module/pdm/item/pdm_item_detail_direct.asp?item_cde=G21796-331&item_rev=01&url_param=unused' | 'DESIGN'      | 'NO'  | '3'   | 'GMPO_BD_EXMPFREE' | '???'
'1.8K'    | '1%'      | '1/16W' | '0402'    | 'EMPTY'  | 'G21796-336'(!) = ''                                 | 'G21796-336' | 'SMR0402A' | '(SMX0402,SMX0402A,SMX0402B)' | 'NA'     | '1%'    | '1/16W' | 'DISCRETE' | 'RES_D,0402,1.80kOHM,1.00%,1/16W,'                      | '0.016 IN' | 'CHIP0402'     | ''          | '1141' | 'http://speed.intel.com:8081/speed/module/pdm/item/pdm_item_detail_direct.asp?item_cde=G21796-336&item_rev=01&url_param=unused' | ''            | ''    | ''    | ''                 | ''   
'1.8K'    | '1%'      | '1/16W' | '0402'    | 'CHIP'   | 'G21796-336'(!) = ''                                 | 'G21796-336' | 'SMR0402A' | '(SMX0402,SMX0402A,SMX0402B)' | '1.8K'   | '1%'    | '1/16W' | 'DISCRETE' | 'RES_D,0402,1.80kOHM,1.00%,1/16W,'                      | '0.016 IN' | 'CHIP0402'     | ''          | '1141' | 'http://speed.intel.com:8081/speed/module/pdm/item/pdm_item_detail_direct.asp?item_cde=G21796-336&item_rev=01&url_param=unused' | ''            | ''    | ''    | ''                 | ''   
'348'     | '1%'      | '1/16W' | '0402'    | 'EMPTY'  | 'G21796-340'(!) = ''                                 | 'G21796-340' | 'SMR0402A' | '(SMX0402,SMX0402A,SMX0402B)' | 'NA'     | '1%'    | '1/16W' | 'DISCRETE' | 'RES_D,0402,348.00OHM,1.00%,1/16W,'                     | '0.016 IN' | 'CHIP0402'     | ''          | '1141' | 'http://speed.intel.com:8081/speed/module/pdm/item/pdm_item_detail_direct.asp?item_cde=G21796-340&item_rev=01&url_param=unused' | ''            | ''    | ''    | ''                 | ''   
'348'     | '1%'      | '1/16W' | '0402'    | 'CHIP'   | 'G21796-340'(!) = ''                                 | 'G21796-340' | 'SMR0402A' | '(SMX0402,SMX0402A,SMX0402B)' | '348'    | '1%'    | '1/16W' | 'DISCRETE' | 'RES_D,0402,348.00OHM,1.00%,1/16W,'                     | '0.016 IN' | 'CHIP0402'     | ''          | '1141' | 'http://speed.intel.com:8081/speed/module/pdm/item/pdm_item_detail_direct.asp?item_cde=G21796-340&item_rev=01&url_param=unused' | ''            | ''    | ''    | ''                 | ''   
'113'     | '1%'      | '1/16W' | '0402'    | 'CHIP'   | 'G21796-341'(!) = ''                                 | 'G21796-341' | 'SMR0402A' | '(SMX0402,SMX0402A,SMX0402B)' | '113'    | '1%'    | '1/16W' | 'DISCRETE' | 'RES_D,0402,113.00OHM,1.00%,1/16W,'                     | '0.016 IN' | 'CHIP0402'     | ''          | '1141' | 'http://speed.intel.com:8081/speed/module/pdm/item/pdm_item_detail_direct.asp?item_cde=G21796-341&item_rev=01&url_param=unused' | ''            | ''    | ''    | ''                 | ''   
'113'     | '1%'      | '1/16W' | '0402'    | 'EMPTY'  | 'G21796-341'(!) = ''                                 | 'G21796-341' | 'SMR0402A' | '(SMX0402,SMX0402A,SMX0402B)' | 'NA'     | '1%'    | '1/16W' | 'DISCRETE' | 'RES_D,0402,113.00OHM,1.00%,1/16W,'                     | '0.016 IN' | 'CHIP0402'     | ''          | '1141' | 'http://speed.intel.com:8081/speed/module/pdm/item/pdm_item_detail_direct.asp?item_cde=G21796-341&item_rev=01&url_param=unused' | ''            | ''    | ''    | ''                 | ''   
'2.7K'    | '1%'      | '1/16W' | '0402'    | 'CHIP'   | 'G21796-344'(!) = ''                                 | 'G21796-344' | 'SMR0402A' | '(SMX0402,SMX0402A,SMX0402B)' | '2.7K'   | '1%'    | '1/16W' | 'DISCRETE' | 'RES_D,0402,2.70kOHM,1.00%,1/16W,'                      | '0.016 IN' | 'CHIP0402'     | ''          | '1141' | 'http://speed.intel.com:8081/speed/module/pdm/item/pdm_item_detail_direct.asp?item_cde=G21796-344&item_rev=01&url_param=unused' | ''            | ''    | ''    | ''                 | ''   
'2.7K'    | '1%'      | '1/16W' | '0402'    | 'EMPTY'  | 'G21796-344'(!) = ''                                 | 'G21796-344' | 'SMR0402A' | '(SMX0402,SMX0402A,SMX0402B)' | 'NA'     | '1%'    | '1/16W' | 'DISCRETE' | 'RES_D,0402,2.70kOHM,1.00%,1/16W,'                      | '0.016 IN' | 'CHIP0402'     | ''          | '1141' | 'http://speed.intel.com:8081/speed/module/pdm/item/pdm_item_detail_direct.asp?item_cde=G21796-344&item_rev=01&url_param=unused' | ''            | ''    | ''    | ''                 | ''   
'8.2K'    | '1%'      | '1/16W' | '0402'    | 'CHIP'   | 'G21796-345'(!) = ''                                 | 'G21796-345' | 'SMR0402A' | '(SMX0402,SMX0402A,SMX0402B)' | '8.2K'   | '1%'    | '1/16W' | 'DISCRETE' | 'RES_D,0402,8.20kOHM,1.00%,1/16W,'                      | '0.016 IN' | 'CHIP0402'     | ''          | '1141' | 'http://speed.intel.com:8081/speed/module/pdm/item/pdm_item_detail_direct.asp?item_cde=G21796-345&item_rev=01&url_param=unused' | ''            | ''    | ''    | ''                 | ''   
'8.2K'    | '1%'      | '1/16W' | '0402'    | 'EMPTY'  | 'G21796-345'(!) = ''                                 | 'G21796-345' | 'SMR0402A' | '(SMX0402,SMX0402A,SMX0402B)' | 'NA'     | '1%'    | '1/16W' | 'DISCRETE' | 'RES_D,0402,8.20kOHM,1.00%,1/16W,'                      | '0.016 IN' | 'CHIP0402'     | ''          | '1141' | 'http://speed.intel.com:8081/speed/module/pdm/item/pdm_item_detail_direct.asp?item_cde=G21796-345&item_rev=01&url_param=unused' | ''            | ''    | ''    | ''                 | ''   
'90.9'    | '1%'      | '1/16W' | '0402'    | 'EMPTY'  | 'G21796-365'(!) = ''                                 | 'G21796-365' | 'SMR0402A' | '(SMX0402,SMX0402A)'          | 'NA'     | '1%'    | '1/16W' | 'DISCRETE' | 'RES_D,0402,90.90OHM,1.00%,1/16W,'                      | '0.016 IN' | 'CHIP0402'     | ''          | '1141' | 'http://speed.intel.com:8081/speed/module/pdm/item/pdm_item_detail_direct.asp?item_cde=G21796-365&item_rev=01&url_param=unused' | ''            | ''    | ''    | ''                 | ''   
'90.9'    | '1%'      | '1/16W' | '0402'    | 'CHIP'   | 'G21796-365'(!) = ''                                 | 'G21796-365' | 'SMR0402A' | '(SMX0402,SMX0402A)'          | '90.9'   | '1%'    | '1/16W' | 'DISCRETE' | 'RES_D,0402,90.90OHM,1.00%,1/16W,'                      | '0.016 IN' | 'CHIP0402'     | ''          | '1141' | 'http://speed.intel.com:8081/speed/module/pdm/item/pdm_item_detail_direct.asp?item_cde=G21796-365&item_rev=01&url_param=unused' | ''            | ''    | ''    | ''                 | ''   
'1.0K'    | '0.1%'    | '1/16W' | '0402'    | 'CHIP'   | 'G85996-004'(!) = 'YES;YES;YES;UNK;OK;VLD'           | 'G85996-004' | 'SMR0402A' | '(SMX0402,SMX0402A,SMX0402B)' | '1.0K'   | '0.1%'  | '1/16W' | 'DISCRETE' | 'RES_D,0402,1.00KOHM,0.1%,1/16W'                        | '0.017 IN' | 'CHIP0402'     | ''          | '1141' | 'http://speed.intel.com:8081/speed/module/pdm/item/pdm_item_detail_direct.asp?item_cde=G85996-004&item_rev=01&url_param=unused' | 'DESIGN'      | 'NO'  | '3'   | 'GMPO_BD_EXMPFREE' | '???'
'1.0K'    | '0.1%'    | '1/16W' | '0402'    | 'EMPTY'  | 'G85996-004'(!) = 'YES;YES;YES;UNK;OK;VLD'           | 'G85996-004' | 'SMR0402A' | '(SMX0402,SMX0402A,SMX0402B)' | 'NA'     | '0.1%'  | '1/16W' | 'DISCRETE' | 'RES_D,0402,1.00KOHM,0.1%,1/16W'                        | '0.017 IN' | 'CHIP0402'     | ''          | '1141' | 'http://speed.intel.com:8081/speed/module/pdm/item/pdm_item_detail_direct.asp?item_cde=G85996-004&item_rev=01&url_param=unused' | 'DESIGN'      | 'NO'  | '3'   | 'GMPO_BD_EXMPFREE' | '???'
'249'     | '0.1%'    | '1/16W' | '0402'    | 'CHIP'   | 'G85996-031'(!) = ''                                 | 'G85996-031' | 'SMR0402A' | '(SMX0402,SMX0402A)'          | '249'    | '0.1%'  | '1/16W' | 'DISCRETE' | 'RES_D,0402,249.00OHM,0.1%,1/16W,'                      | '0.016 IN' | 'CHIP0402'     | ''          | '1141' | 'http://speed.intel.com:8081/speed/module/pdm/item/pdm_item_detail_direct.asp?item_cde=G85996-031&item_rev=01&url_param=unused' | ''            | ''    | ''    | ''                 | ''   
'249'     | '0.1%'    | '1/16W' | '0402'    | 'EMPTY'  | 'G85996-031'(!) = ''                                 | 'G85996-031' | 'SMR0402A' | '(SMX0402,SMX0402A)'          | 'NA'     | '0.1%'  | '1/16W' | 'DISCRETE' | 'RES_D,0402,249.00OHM,0.1%,1/16W,'                      | '0.016 IN' | 'CHIP0402'     | ''          | '1141' | 'http://speed.intel.com:8081/speed/module/pdm/item/pdm_item_detail_direct.asp?item_cde=G85996-031&item_rev=01&url_param=unused' | ''            | ''    | ''    | ''                 | ''   
'120.0'   | '1%'      | '1/10W' | '0603'    | 'CHIP'   | 'G22026-003'(!) = 'YES;YES;YES;UNK;OK;VLD'           | 'G22026-003' | 'SMR0603A' | '(SMX0603)'                   | '120.0'  | '1%'    | '1/10W' | 'DISCRETE' | 'RES_D,0603,120.0OHM,1.00%,1/10W'                       | '0.024 IN' | 'CHIP0603'     | ''          | '247'  | 'http://speed.intel.com:8081/speed/module/pdm/item/pdm_item_detail_direct.asp?item_cde=G22026-003&item_rev=01&url_param=unused' | 'DESIGN'      | 'NO'  | '3'   | 'GMPO_BD_EXMPFREE' | '???'
'120.0'   | '1%'      | '1/10W' | '0603'    | 'EMPTY'  | 'G22026-003'(!) = 'YES;YES;YES;UNK;OK;VLD'           | 'G22026-003' | 'SMR0603A' | '(SMX0603)'                   | 'NA'     | '1%'    | '1/10W' | 'DISCRETE' | 'RES_D,0603,120.0OHM,1.00%,1/10W'                       | '0.024 IN' | 'CHIP0603'     | ''          | '247'  | 'http://speed.intel.com:8081/speed/module/pdm/item/pdm_item_detail_direct.asp?item_cde=G22026-003&item_rev=01&url_param=unused' | 'DESIGN'      | 'NO'  | '3'   | 'GMPO_BD_EXMPFREE' | '???'
'475.0'   | '1%'      | '1/10W' | '0603'    | 'EMPTY'  | 'G22026-030'(!) = 'YES;YES;YES;UNK;OK;VLD'           | 'G22026-030' | 'SMR0603A' | '(SMX0603)'                   | 'NA'     | '1%'    | '1/10W' | 'DISCRETE' | 'RES_D,0603,475.0OHM,1.00%,1/10W'                       | '0.024 IN' | 'CHIP0603'     | ''          | '247'  | 'http://speed.intel.com:8081/speed/module/pdm/item/pdm_item_detail_direct.asp?item_cde=G22026-030&item_rev=01&url_param=unused' | 'DESIGN'      | 'NO'  | '3'   | 'GMPO_BD_EXMPFREE' | '???'
'475.0'   | '1%'      | '1/10W' | '0603'    | 'CHIP'   | 'G22026-030'(!) = 'YES;YES;YES;UNK;OK;VLD'           | 'G22026-030' | 'SMR0603A' | '(SMX0603)'                   | '475.0'  | '1%'    | '1/10W' | 'DISCRETE' | 'RES_D,0603,475.0OHM,1.00%,1/10W'                       | '0.024 IN' | 'CHIP0603'     | ''          | '247'  | 'http://speed.intel.com:8081/speed/module/pdm/item/pdm_item_detail_direct.asp?item_cde=G22026-030&item_rev=01&url_param=unused' | 'DESIGN'      | 'NO'  | '3'   | 'GMPO_BD_EXMPFREE' | '???'
'100.0'   | '1%'      | '1/10W' | '0603'    | 'CHIP'   | 'G22026-038'(!) = 'YES;YES;YES;UNK;OK;VLD'           | 'G22026-038' | 'SMR0603A' | '(SMX0603)'                   | '100.0'  | '1%'    | '1/10W' | 'DISCRETE' | 'RES_D,0603,100.00OHM,1.00%,1/10W'                      | '0.024 IN' | 'CHIP0603'     | ''          | '247'  | 'http://speed.intel.com:8081/speed/module/pdm/item/pdm_item_detail_direct.asp?item_cde=G22026-038&item_rev=01&url_param=unused' | 'DESIGN'      | 'NO'  | '4'   | 'GMPO_BD_EXMPFREE' | '???'
'100.0'   | '1%'      | '1/10W' | '0603'    | 'EMPTY'  | 'G22026-038'(!) = 'YES;YES;YES;UNK;OK;VLD'           | 'G22026-038' | 'SMR0603A' | '(SMX0603)'                   | 'NA'     | '1%'    | '1/10W' | 'DISCRETE' | 'RES_D,0603,100.00OHM,1.00%,1/10W'                      | '0.024 IN' | 'CHIP0603'     | ''          | '247'  | 'http://speed.intel.com:8081/speed/module/pdm/item/pdm_item_detail_direct.asp?item_cde=G22026-038&item_rev=01&url_param=unused' | 'DESIGN'      | 'NO'  | '4'   | 'GMPO_BD_EXMPFREE' | '???'
'10.0'    | '1%'      | '1/10W' | '0603'    | 'CHIP'   | 'G22026-041'(!) = 'YES;YES;YES;UNK;OK;VLD'           | 'G22026-041' | 'SMR0603A' | '(SMX0603)'                   | '10.0'   | '1%'    | '1/10W' | 'DISCRETE' | 'RES_D,0603,10.00OHM,1.00%,1/10W'                       | '0.024 IN' | 'CHIP0603'     | ''          | '247'  | 'http://speed.intel.com:8081/speed/module/pdm/item/pdm_item_detail_direct.asp?item_cde=G22026-041&item_rev=01&url_param=unused' | 'UNQUAL'      | 'NO'  | '3'   | 'GMPO_BD_EXMPFREE' | '???'
'10.0'    | '1%'      | '1/10W' | '0603'    | 'EMPTY'  | 'G22026-041'(!) = 'YES;YES;YES;UNK;OK;VLD'           | 'G22026-041' | 'SMR0603A' | '(SMX0603)'                   | 'NA'     | '1%'    | '1/10W' | 'DISCRETE' | 'RES_D,0603,10.00OHM,1.00%,1/10W'                       | '0.024 IN' | 'CHIP0603'     | ''          | '247'  | 'http://speed.intel.com:8081/speed/module/pdm/item/pdm_item_detail_direct.asp?item_cde=G22026-041&item_rev=01&url_param=unused' | 'UNQUAL'      | 'NO'  | '3'   | 'GMPO_BD_EXMPFREE' | '???'
'100.0K'  | '1%'      | '1/10W' | '0603'    | 'CHIP'   | 'G22026-050'(!) = 'YES;YES;YES;UNK;OK;VLD'           | 'G22026-050' | 'SMR0603A' | '(SMX0603)'                   | '100.0K' | '1%'    | '1/10W' | 'DISCRETE' | 'RES_D,0603,100.00KOHM,1.00%,1/10W'                     | '0.024 IN' | 'CHIP0603'     | ''          | '247'  | 'http://speed.intel.com:8081/speed/module/pdm/item/pdm_item_detail_direct.asp?item_cde=G22026-050&item_rev=01&url_param=unused' | 'DESIGN'      | 'NO'  | '3'   | 'GMPO_BD_EXMPFREE' | '???'
'100.0K'  | '1%'      | '1/10W' | '0603'    | 'EMPTY'  | 'G22026-050'(!) = 'YES;YES;YES;UNK;OK;VLD'           | 'G22026-050' | 'SMR0603A' | '(SMX0603)'                   | 'NA'     | '1%'    | '1/10W' | 'DISCRETE' | 'RES_D,0603,100.00KOHM,1.00%,1/10W'                     | '0.024 IN' | 'CHIP0603'     | ''          | '247'  | 'http://speed.intel.com:8081/speed/module/pdm/item/pdm_item_detail_direct.asp?item_cde=G22026-050&item_rev=01&url_param=unused' | 'DESIGN'      | 'NO'  | '3'   | 'GMPO_BD_EXMPFREE' | '???'
'10M'     | '1.0%'    | '1/10W' | '0603'    | 'EMPTY'  | 'G22026-112'(!) = 'YES;YES;YES;UNK;OK;VLD'           | 'G22026-112' | 'SMR0603A' | '(SMX0603)'                   | 'NA'     | '1.0%'  | '1/10W' | 'DISCRETE' | 'RES_D,0603,10.00MOHM,1.00%,1/10W,'                     | '0.024 IN' | 'CHIP0603'     | ''          | '247'  | 'http://speed.intel.com:8081/speed/module/pdm/item/pdm_item_detail_direct.asp?item_cde=G22026-112&item_rev=01&url_param=unused' | 'DESIGN'      | 'NO'  | '2'   | 'GMPO_BD_EXMPFREE' | '???'
'10M'     | '1.0%'    | '1/10W' | '0603'    | 'CHIP'   | 'G22026-112'(!) = 'YES;YES;YES;UNK;OK;VLD'           | 'G22026-112' | 'SMR0603A' | '(SMX0603)'                   | '10M'    | '1.0%'  | '1/10W' | 'DISCRETE' | 'RES_D,0603,10.00MOHM,1.00%,1/10W,'                     | '0.024 IN' | 'CHIP0603'     | ''          | '247'  | 'http://speed.intel.com:8081/speed/module/pdm/item/pdm_item_detail_direct.asp?item_cde=G22026-112&item_rev=01&url_param=unused' | 'DESIGN'      | 'NO'  | '2'   | 'GMPO_BD_EXMPFREE' | '???'
'2.2'     | '1.0%'    | '1/10W' | '0603'    | 'EMPTY'  | 'G22026-127'(!) = 'UNK;UNK;UNK;UNK;OK;CIP'           | 'G22026-127' | 'SMR0603A' | '(SMX0603)'                   | 'NA'     | '1.0%'  | '1/10W' | 'DISCRETE' | 'RES_D,0603,2.20OHM,1.00%,1/10W,'                       | '0.024 IN' | 'CHIP0603'     | ''          | '247'  | 'http://speed.intel.com:8081/speed/module/pdm/item/pdm_item_detail_direct.asp?item_cde=G22026-127&item_rev=01&url_param=unused' | 'DESIGN'      | 'NO'  | '2'   | 'GMPO_BD_EXMPFREE' | '???'
'2.2'     | '1.0%'    | '1/10W' | '0603'    | 'CHIP'   | 'G22026-127'(!) = 'UNK;UNK;UNK;UNK;OK;CIP'           | 'G22026-127' | 'SMR0603A' | '(SMX0603)'                   | '2.2'    | '1.0%'  | '1/10W' | 'DISCRETE' | 'RES_D,0603,2.20OHM,1.00%,1/10W,'                       | '0.024 IN' | 'CHIP0603'     | ''          | '247'  | 'http://speed.intel.com:8081/speed/module/pdm/item/pdm_item_detail_direct.asp?item_cde=G22026-127&item_rev=01&url_param=unused' | 'DESIGN'      | 'NO'  | '2'   | 'GMPO_BD_EXMPFREE' | '???'
'0'       | '5.0%'    | '1/10W' | '0603'    | 'CHIP'   | 'G22178-002'(!) = 'YES;YES;YES;UNK;OK;VLD'           | 'G22178-002' | 'SMR0603A' | '(SMX0603)'                   | '0'      | '5.0%'  | '1/10W' | 'DISCRETE' | 'RES_D,0603,0.00OHM,5.00%,1/10W,'                       | '0.024 IN' | 'CHIP0603'     | ''          | '247'  | 'http://speed.intel.com:8081/speed/module/pdm/item/pdm_item_detail_direct.asp?item_cde=G22178-002&item_rev=01&url_param=unused' | 'UNQUAL'      | 'NO'  | '3'   | 'GMPO_BD_EXMPFREE' | '???'
'0'       | '5.0%'    | '1/10W' | '0603'    | 'EMPTY'  | 'G22178-002'(!) = 'YES;YES;YES;UNK;OK;VLD'           | 'G22178-002' | 'SMR0603A' | '(SMX0603)'                   | 'NA'     | '5.0%'  | '1/10W' | 'DISCRETE' | 'RES_D,0603,0.00OHM,5.00%,1/10W,'                       | '0.024 IN' | 'CHIP0603'     | ''          | '247'  | 'http://speed.intel.com:8081/speed/module/pdm/item/pdm_item_detail_direct.asp?item_cde=G22178-002&item_rev=01&url_param=unused' | 'UNQUAL'      | 'NO'  | '3'   | 'GMPO_BD_EXMPFREE' | '???'
'200K'    | '0.1%'    | '1/10W' | '0603'    | 'CHIP'   | 'G22369-010'(!) = ''                                 | 'G22369-010' | 'SMR0603A' | '(SMX0603)'                   | '200K'   | '0.1%'  | '1/10W' | 'DISCRETE' | 'RES_D,0603,200.00kOHM,0.1%,1/10W,'                     | '0.024 IN' | 'CHIP0603'     | ''          | '247'  | 'http://speed.intel.com:8081/speed/module/pdm/item/pdm_item_detail_direct.asp?item_cde=G22369-010&item_rev=01&url_param=unused' | ''            | ''    | ''    | ''                 | ''   
'200K'    | '0.1%'    | '1/10W' | '0603'    | 'EMPTY'  | 'G22369-010'(!) = ''                                 | 'G22369-010' | 'SMR0603A' | '(SMX0603)'                   | 'NA'     | '0.1%'  | '1/10W' | 'DISCRETE' | 'RES_D,0603,200.00kOHM,0.1%,1/10W,'                     | '0.024 IN' | 'CHIP0603'     | ''          | '247'  | 'http://speed.intel.com:8081/speed/module/pdm/item/pdm_item_detail_direct.asp?item_cde=G22369-010&item_rev=01&url_param=unused' | ''            | ''    | ''    | ''                 | ''   
'0.0'     | '5%'      | '1/8W'  | '0805'    | 'CHIP'   | 'G22179-004'(!) = 'YES;YES;YES;UNK;OK;VLD'           | 'G22179-004' | 'SMR0805A' | '(SMX0805)'                   | '0.0'    | '5%'    | '1/8W'  | 'DISCRETE' | 'RES_D,0805,0.00OHM,5.00%,1/8W'                         | '0.026 IN' | 'CHIP0805'     | ''          | '248'  | 'http://speed.intel.com:8081/speed/module/pdm/item/pdm_item_detail_direct.asp?item_cde=G22179-004&item_rev=01&url_param=unused' | 'UNQUAL'      | 'NO'  | '2'   | 'GMPO_BD_EXMPFREE' | '???'
'0.0'     | '5%'      | '1/8W'  | '0805'    | 'EMPTY'  | 'G22179-004'(!) = 'YES;YES;YES;UNK;OK;VLD'           | 'G22179-004' | 'SMR0805A' | '(SMX0805)'                   | 'NA'     | '5%'    | '1/8W'  | 'DISCRETE' | 'RES_D,0805,0.00OHM,5.00%,1/8W'                         | '0.026 IN' | 'CHIP0805'     | ''          | '248'  | 'http://speed.intel.com:8081/speed/module/pdm/item/pdm_item_detail_direct.asp?item_cde=G22179-004&item_rev=01&url_param=unused' | 'UNQUAL'      | 'NO'  | '2'   | 'GMPO_BD_EXMPFREE' | '???'
'0.002'   | '1%'      | '1W'    | '1206'    | 'CHIP'   | 'G52199-004'(!) = 'YES;YES;YES;UNK;OK;VLD'           | 'G52199-004' | 'SMR1206A' | ''                            | '0.002'  | '1%'    | '1W'    | 'DISCRETE' | '0.002OHM 1206LF'                                       | '0.035 IN' | 'CHIP'         | ''          | '249'  | 'http://speed.intel.com:8081/speed/module/pdm/item/pdm_item_detail_direct.asp?item_cde=G52199-004&item_rev=01&url_param=unused' | 'DESIGN'      | 'NO'  | '1'   | 'SMO_BOARDS'       | '???'
'0.002'   | '1%'      | '1W'    | '1206'    | 'EMPTY'  | 'G52199-004'(!) = 'YES;YES;YES;UNK;OK;VLD'           | 'G52199-004' | 'SMR1206A' | ''                            | 'NA'     | '1%'    | '1W'    | 'DISCRETE' | '0.002OHM 1206LF'                                       | '0.035 IN' | 'CHIP'         | ''          | '249'  | 'http://speed.intel.com:8081/speed/module/pdm/item/pdm_item_detail_direct.asp?item_cde=G52199-004&item_rev=01&url_param=unused' | 'DESIGN'      | 'NO'  | '1'   | 'SMO_BOARDS'       | '???'
'0.001'   | '1%'      | '1W'    | '2010'    | 'CHIP'   | 'E30969-002'(!) = 'YES;YES;UNK;UNK;OK;VLD'           | 'E30969-002' | 'SMR2010B' | ''                            | '0.001'  | '1%'    | '1W'    | 'DISCRETE' | 'RES D,2010,1.00 MOHM,1.00%,1W,YES'                     | '0.035 IN' | 'CHIP'         | ''          | '3309' | 'http://speed.intel.com:8081/speed/module/pdm/item/pdm_item_detail_direct.asp?item_cde=E30969-002&item_rev=01&url_param=unused' | 'DESIGN'      | 'NO'  | '2'   | 'SMO_BOARDS'       | '???'
'0.001'   | '1%'      | '1W'    | '2010'    | 'EMPTY'  | 'E30969-002'(!) = 'YES;YES;UNK;UNK;OK;VLD'           | 'E30969-002' | 'SMR2010B' | ''                            | 'NA'     | '1%'    | '1W'    | 'DISCRETE' | 'RES D,2010,1.00 MOHM,1.00%,1W,YES'                     | '0.035 IN' | 'CHIP'         | ''          | '3309' | 'http://speed.intel.com:8081/speed/module/pdm/item/pdm_item_detail_direct.asp?item_cde=E30969-002&item_rev=01&url_param=unused' | 'DESIGN'      | 'NO'  | '2'   | 'SMO_BOARDS'       | '???'
END_PART
END.
